G04 ================== begin FILE IDENTIFICATION RECORD ==================*
G04 Layout Name:  13948-1b.brd*
G04 Film Name:    L5VCC*
G04 File Format:  Gerber RS274X*
G04 File Origin:  Cadence Allegro 16.5-S045*
G04 Origin Date:  Thu Nov 13 15:46:15 2014*
G04 *
G04 Layer:  VIA CLASS/L5VCC*
G04 Layer:  PIN/L5VCC*
G04 Layer:  PACKAGE GEOMETRY/PWRVCC*
G04 Layer:  ETCH/L5VCC*
G04 Layer:  DRAWING FORMAT/LAYER_PCB_STORY*
G04 Layer:  DRAWING FORMAT/LAYER_L5VCC*
G04 *
G04 Offset:    (0.00 0.00)*
G04 Mirror:    No*
G04 Mode:      Negative*
G04 Rotation:  0*
G04 FullContactRelief:  No*
G04 UndefLineWidth:     6.00*
G04 ================== end FILE IDENTIFICATION RECORD ====================*
%FSLAX35Y35*MOIN*%
%IR0*IPPOS*OFA0.00000B0.00000*MIA0B0*SFA1.00000B1.00000*%
%ADD17C,.03*%
%ADD13C,.032*%
%ADD47C,.06*%
%ADD43C,.07*%
%ADD42C,.062*%
%ADD19C,.036*%
%ADD18C,.063*%
%ADD12C,.09*%
%ADD36C,.064*%
%ADD22C,.073*%
%ADD39C,.066*%
%ADD31C,.057*%
%ADD41C,.076*%
%ADD28C,.059*%
%ADD24C,.068*%
%ADD33C,.078*%
%ADD15C,.089*%
%AMMACRO44*
4,1,14,.02707,.01293,
.028904,.008033,
.02986,.002892,
.029908,-.002337,
.029048,-.007495,
.027305,-.012426,
.02707,-.01293,
.03079,-.01665,
.033213,-.01105,
.034628,-.005115,
.03499,.000976,
.034289,.007037,
.032546,.012884,
.03079,.01665,
.02707,.01293,
270.*
4,1,14,.01293,-.02707,
.008033,-.028904,
.002892,-.02986,
-.002337,-.029908,
-.007495,-.029048,
-.012426,-.027305,
-.01293,-.02707,
-.01665,-.03079,
-.01105,-.033213,
-.005115,-.034628,
.000976,-.03499,
.007037,-.034289,
.012884,-.032546,
.01665,-.03079,
.01293,-.02707,
270.*
4,1,14,-.02707,-.01293,
-.028904,-.008033,
-.02986,-.002892,
-.029908,.002337,
-.029048,.007495,
-.027305,.012426,
-.02707,.01293,
-.03079,.01665,
-.033213,.01105,
-.034628,.005115,
-.03499,-.000976,
-.034289,-.007037,
-.032546,-.012884,
-.03079,-.01665,
-.02707,-.01293,
270.*
4,1,14,-.01293,.02707,
-.008033,.028904,
-.002892,.02986,
.002337,.029908,
.007495,.029048,
.012426,.027305,
.01293,.02707,
.01665,.03079,
.01105,.033213,
.005115,.034628,
-.000976,.03499,
-.007037,.034289,
-.012884,.032546,
-.01665,.03079,
-.01293,.02707,
270.*
%
%ADD44MACRO44*%
%AMMACRO29*
4,1,15,.00398,.00044,
.003999,.000208,
.004004,-.000025,
.003996,-.000258,
.00398,-.00044,
.00483,-.00129,
.004897,-.001007,
.004947,-.000721,
.004981,-.000432,
.004997,-.000141,
.004997,.000149,
.00498,.00044,
.004946,.000729,
.004895,.001015,
.00483,.00129,
.00398,.00044,
90.*
4,1,15,.00044,-.00398,
.000208,-.003999,
-.000025,-.004004,
-.000258,-.003996,
-.00044,-.00398,
-.00129,-.00483,
-.001007,-.004897,
-.000721,-.004947,
-.000432,-.004981,
-.000141,-.004997,
.000149,-.004997,
.00044,-.00498,
.000729,-.004946,
.001015,-.004895,
.00129,-.00483,
.00044,-.00398,
90.*
4,1,15,-.00398,-.00044,
-.003999,-.000208,
-.004004,.000025,
-.003996,.000258,
-.00398,.00044,
-.00483,.00129,
-.004897,.001007,
-.004947,.000721,
-.004981,.000432,
-.004997,.000141,
-.004997,-.000149,
-.00498,-.00044,
-.004946,-.000729,
-.004895,-.001015,
-.00483,-.00129,
-.00398,-.00044,
90.*
4,1,15,-.00044,.00398,
-.000208,.003999,
.000025,.004004,
.000258,.003996,
.00044,.00398,
.00129,.00483,
.001007,.004897,
.000721,.004947,
.000432,.004981,
.000141,.004997,
-.000149,.004997,
-.00044,.00498,
-.000729,.004946,
-.001015,.004895,
-.00129,.00483,
-.00044,.00398,
90.*
%
%ADD29MACRO29*%
%AMMACRO10*
4,1,15,.00398,.00044,
.003999,.000208,
.004004,-.000025,
.003996,-.000258,
.00398,-.00044,
.00483,-.00129,
.004897,-.001007,
.004947,-.000721,
.004981,-.000432,
.004997,-.000141,
.004997,.000149,
.00498,.00044,
.004946,.000729,
.004895,.001015,
.00483,.00129,
.00398,.00044,
0.0*
4,1,15,.00044,-.00398,
.000208,-.003999,
-.000025,-.004004,
-.000258,-.003996,
-.00044,-.00398,
-.00129,-.00483,
-.001007,-.004897,
-.000721,-.004947,
-.000432,-.004981,
-.000141,-.004997,
.000149,-.004997,
.00044,-.00498,
.000729,-.004946,
.001015,-.004895,
.00129,-.00483,
.00044,-.00398,
0.0*
4,1,15,-.00398,-.00044,
-.003999,-.000208,
-.004004,.000025,
-.003996,.000258,
-.00398,.00044,
-.00483,.00129,
-.004897,.001007,
-.004947,.000721,
-.004981,.000432,
-.004997,.000141,
-.004997,-.000149,
-.00498,-.00044,
-.004946,-.000729,
-.004895,-.001015,
-.00483,-.00129,
-.00398,-.00044,
0.0*
4,1,15,-.00044,.00398,
-.000208,.003999,
.000025,.004004,
.000258,.003996,
.00044,.00398,
.00129,.00483,
.001007,.004897,
.000721,.004947,
.000432,.004981,
.000141,.004997,
-.000149,.004997,
-.00044,.00498,
-.000729,.004946,
-.001015,.004895,
-.00129,.00483,
-.00044,.00398,
0.0*
%
%ADD10MACRO10*%
%AMMACRO45*
4,1,13,.02442,.01028,
.025834,.005883,
.026463,.001308,
.026288,-.003307,
.025315,-.007822,
.02442,-.01028,
.02819,-.01405,
.030201,-.008941,
.031295,-.003561,
.031438,.001927,
.030626,.007357,
.028883,.012564,
.02819,.01405,
.02442,.01028,
180.*
4,1,13,.01028,-.02442,
.005883,-.025834,
.001308,-.026463,
-.003307,-.026288,
-.007822,-.025315,
-.01028,-.02442,
-.01405,-.02819,
-.008941,-.030201,
-.003561,-.031295,
.001927,-.031438,
.007357,-.030626,
.012564,-.028883,
.01405,-.02819,
.01028,-.02442,
180.*
4,1,13,-.02442,-.01028,
-.025834,-.005883,
-.026463,-.001308,
-.026288,.003307,
-.025315,.007822,
-.02442,.01028,
-.02819,.01405,
-.030201,.008941,
-.031295,.003561,
-.031438,-.001927,
-.030626,-.007357,
-.028883,-.012564,
-.02819,-.01405,
-.02442,-.01028,
180.*
4,1,13,-.01028,.02442,
-.005883,.025834,
-.001308,.026463,
.003307,.026288,
.007822,.025315,
.01028,.02442,
.01405,.02819,
.008941,.030201,
.003561,.031295,
-.001927,.031438,
-.007357,.030626,
-.012564,.028883,
-.01405,.02819,
-.01028,.02442,
180.*
%
%ADD45MACRO45*%
%AMMACRO32*
4,1,19,.02211,.00797,
.022536,.006671,
.022886,.005349,
.023158,.00401,
.023352,.002656,
.023467,.001294,
.023503,-.000073,
.023459,-.001439,
.023335,-.002801,
.023133,-.004153,
.022852,-.005491,
.022494,-.00681,
.02211,-.00797,
.02594,-.0118,
.027595,-.007116,
.028411,-.002216,
.028365,.002751,
.027456,.007635,
.02594,.0118,
.02211,.00797,
180.*
4,1,19,.00797,-.02211,
.006671,-.022536,
.005349,-.022886,
.00401,-.023158,
.002656,-.023352,
.001294,-.023467,
-.000073,-.023503,
-.001439,-.023459,
-.002801,-.023335,
-.004153,-.023133,
-.005491,-.022852,
-.00681,-.022494,
-.00797,-.02211,
-.0118,-.02594,
-.007116,-.027595,
-.002216,-.028411,
.002751,-.028365,
.007635,-.027456,
.0118,-.02594,
.00797,-.02211,
180.*
4,1,19,-.02211,-.00797,
-.022536,-.006671,
-.022886,-.005349,
-.023158,-.00401,
-.023352,-.002656,
-.023467,-.001294,
-.023503,.000073,
-.023459,.001439,
-.023335,.002801,
-.023133,.004153,
-.022852,.005491,
-.022494,.00681,
-.02211,.00797,
-.02594,.0118,
-.027595,.007116,
-.028411,.002216,
-.028365,-.002751,
-.027456,-.007635,
-.02594,-.0118,
-.02211,-.00797,
180.*
4,1,19,-.00797,.02211,
-.006671,.022536,
-.005349,.022886,
-.00401,.023158,
-.002656,.023352,
-.001294,.023467,
.000073,.023503,
.001439,.023459,
.002801,.023335,
.004153,.023133,
.005491,.022852,
.00681,.022494,
.00797,.02211,
.0118,.02594,
.007116,.027595,
.002216,.028411,
-.002751,.028365,
-.007635,.027456,
-.0118,.02594,
-.00797,.02211,
180.*
%
%ADD32MACRO32*%
%AMMACRO46*
4,1,13,.02632,.01218,
.028035,.007425,
.028899,.002443,
.028884,-.002612,
.027991,-.007588,
.02632,-.01218,
.03005,-.01591,
.032356,-.01045,
.033679,-.004673,
.033979,.001247,
.033246,.007128,
.031504,.012793,
.03005,.01591,
.02632,.01218,
180.*
4,1,13,.01218,-.02632,
.007425,-.028035,
.002443,-.028899,
-.002612,-.028884,
-.007588,-.027991,
-.01218,-.02632,
-.01591,-.03005,
-.01045,-.032356,
-.004673,-.033679,
.001247,-.033979,
.007128,-.033246,
.012793,-.031504,
.01591,-.03005,
.01218,-.02632,
180.*
4,1,13,-.02632,-.01218,
-.028035,-.007425,
-.028899,-.002443,
-.028884,.002612,
-.027991,.007588,
-.02632,.01218,
-.03005,.01591,
-.032356,.01045,
-.033679,.004673,
-.033979,-.001247,
-.033246,-.007128,
-.031504,-.012793,
-.03005,-.01591,
-.02632,-.01218,
180.*
4,1,13,-.01218,.02632,
-.007425,.028035,
-.002443,.028899,
.002612,.028884,
.007588,.027991,
.01218,.02632,
.01591,.03005,
.01045,.032356,
.004673,.033679,
-.001247,.033979,
-.007128,.033246,
-.012793,.031504,
-.01591,.03005,
-.01218,.02632,
180.*
%
%ADD46MACRO46*%
%AMMACRO23*
4,1,13,.02632,.01218,
.028035,.007425,
.028899,.002443,
.028884,-.002612,
.027991,-.007588,
.02632,-.01218,
.03005,-.01591,
.032356,-.01045,
.033679,-.004673,
.033979,.001247,
.033246,.007128,
.031504,.012793,
.03005,.01591,
.02632,.01218,
270.*
4,1,13,.01218,-.02632,
.007425,-.028035,
.002443,-.028899,
-.002612,-.028884,
-.007588,-.027991,
-.01218,-.02632,
-.01591,-.03005,
-.01045,-.032356,
-.004673,-.033679,
.001247,-.033979,
.007128,-.033246,
.012793,-.031504,
.01591,-.03005,
.01218,-.02632,
270.*
4,1,13,-.02632,-.01218,
-.028035,-.007425,
-.028899,-.002443,
-.028884,.002612,
-.027991,.007588,
-.02632,.01218,
-.03005,.01591,
-.032356,.01045,
-.033679,.004673,
-.033979,-.001247,
-.033246,-.007128,
-.031504,-.012793,
-.03005,-.01591,
-.02632,-.01218,
270.*
4,1,13,-.01218,.02632,
-.007425,.028035,
-.002443,.028899,
.002612,.028884,
.007588,.027991,
.01218,.02632,
.01591,.03005,
.01045,.032356,
.004673,.033679,
-.001247,.033979,
-.007128,.033246,
-.012793,.031504,
-.01591,.03005,
-.01218,.02632,
270.*
%
%ADD23MACRO23*%
%ADD37O,.217X.154*%
%ADD30C,.121*%
%ADD14C,.114*%
%ADD26C,.154*%
%ADD38C,.119*%
%ADD35C,.156*%
%ADD27C,.166*%
%AMMACRO20*
4,1,15,.00398,.00044,
.003999,.000208,
.004004,-.000025,
.003996,-.000258,
.00398,-.00044,
.00483,-.00129,
.004897,-.001007,
.004947,-.000721,
.004981,-.000432,
.004997,-.000141,
.004997,.000149,
.00498,.00044,
.004946,.000729,
.004895,.001015,
.00483,.00129,
.00398,.00044,
180.*
4,1,15,.00044,-.00398,
.000208,-.003999,
-.000025,-.004004,
-.000258,-.003996,
-.00044,-.00398,
-.00129,-.00483,
-.001007,-.004897,
-.000721,-.004947,
-.000432,-.004981,
-.000141,-.004997,
.000149,-.004997,
.00044,-.00498,
.000729,-.004946,
.001015,-.004895,
.00129,-.00483,
.00044,-.00398,
180.*
4,1,15,-.00398,-.00044,
-.003999,-.000208,
-.004004,.000025,
-.003996,.000258,
-.00398,.00044,
-.00483,.00129,
-.004897,.001007,
-.004947,.000721,
-.004981,.000432,
-.004997,.000141,
-.004997,-.000149,
-.00498,-.00044,
-.004946,-.000729,
-.004895,-.001015,
-.00483,-.00129,
-.00398,-.00044,
180.*
4,1,15,-.00044,.00398,
-.000208,.003999,
.000025,.004004,
.000258,.003996,
.00044,.00398,
.00129,.00483,
.001007,.004897,
.000721,.004947,
.000432,.004981,
.000141,.004997,
-.000149,.004997,
-.00044,.00498,
-.000729,.004946,
-.001015,.004895,
-.00129,.00483,
-.00044,.00398,
180.*
%
%ADD20MACRO20*%
%AMMACRO16*
4,1,15,.00398,.00044,
.003999,.000208,
.004004,-.000025,
.003996,-.000258,
.00398,-.00044,
.00483,-.00129,
.004897,-.001007,
.004947,-.000721,
.004981,-.000432,
.004997,-.000141,
.004997,.000149,
.00498,.00044,
.004946,.000729,
.004895,.001015,
.00483,.00129,
.00398,.00044,
270.*
4,1,15,.00044,-.00398,
.000208,-.003999,
-.000025,-.004004,
-.000258,-.003996,
-.00044,-.00398,
-.00129,-.00483,
-.001007,-.004897,
-.000721,-.004947,
-.000432,-.004981,
-.000141,-.004997,
.000149,-.004997,
.00044,-.00498,
.000729,-.004946,
.001015,-.004895,
.00129,-.00483,
.00044,-.00398,
270.*
4,1,15,-.00398,-.00044,
-.003999,-.000208,
-.004004,.000025,
-.003996,.000258,
-.00398,.00044,
-.00483,.00129,
-.004897,.001007,
-.004947,.000721,
-.004981,.000432,
-.004997,.000141,
-.004997,-.000149,
-.00498,-.00044,
-.004946,-.000729,
-.004895,-.001015,
-.00483,-.00129,
-.00398,-.00044,
270.*
4,1,15,-.00044,.00398,
-.000208,.003999,
.000025,.004004,
.000258,.003996,
.00044,.00398,
.00129,.00483,
.001007,.004897,
.000721,.004947,
.000432,.004981,
.000141,.004997,
-.000149,.004997,
-.00044,.00498,
-.000729,.004946,
-.001015,.004895,
-.00129,.00483,
-.00044,.00398,
270.*
%
%ADD16MACRO16*%
%AMMACRO21*
4,1,13,.02327,.00913,
.024502,.004951,
.024989,.000621,
.024717,-.003728,
.023695,-.007964,
.02327,-.00913,
.02707,-.01293,
.028904,-.008033,
.02986,-.002892,
.029908,.002337,
.029048,.007495,
.027305,.012426,
.02707,.01293,
.02327,.00913,
0.0*
4,1,13,.00913,-.02327,
.004951,-.024502,
.000621,-.024989,
-.003728,-.024717,
-.007964,-.023695,
-.00913,-.02327,
-.01293,-.02707,
-.008033,-.028904,
-.002892,-.02986,
.002337,-.029908,
.007495,-.029048,
.012426,-.027305,
.01293,-.02707,
.00913,-.02327,
0.0*
4,1,13,-.02327,-.00913,
-.024502,-.004951,
-.024989,-.000621,
-.024717,.003728,
-.023695,.007964,
-.02327,.00913,
-.02707,.01293,
-.028904,.008033,
-.02986,.002892,
-.029908,-.002337,
-.029048,-.007495,
-.027305,-.012426,
-.02707,-.01293,
-.02327,-.00913,
0.0*
4,1,13,-.00913,.02327,
-.004951,.024502,
-.000621,.024989,
.003728,.024717,
.007964,.023695,
.00913,.02327,
.01293,.02707,
.008033,.028904,
.002892,.02986,
-.002337,.029908,
-.007495,.029048,
-.012426,.027305,
-.01293,.02707,
-.00913,.02327,
0.0*
%
%ADD21MACRO21*%
%AMMACRO34*
4,1,13,.03683,.01561,
.038981,.008977,
.039948,.002072,
.039701,-.004896,
.038247,-.011716,
.03683,-.01561,
.04061,-.01939,
.04336,-.012044,
.044793,-.004331,
.044864,.003513,
.043573,.01125,
.040957,.018645,
.04061,.01939,
.03683,.01561,
0.0*
4,1,13,.01561,-.03683,
.008977,-.038981,
.002072,-.039948,
-.004896,-.039701,
-.011716,-.038247,
-.01561,-.03683,
-.01939,-.04061,
-.012044,-.04336,
-.004331,-.044793,
.003513,-.044864,
.01125,-.043573,
.018645,-.040957,
.01939,-.04061,
.01561,-.03683,
0.0*
4,1,13,-.03683,-.01561,
-.038981,-.008977,
-.039948,-.002072,
-.039701,.004896,
-.038247,.011716,
-.03683,.01561,
-.04061,.01939,
-.04336,.012044,
-.044793,.004331,
-.044864,-.003513,
-.043573,-.01125,
-.040957,-.018645,
-.04061,-.01939,
-.03683,-.01561,
0.0*
4,1,13,-.01561,.03683,
-.008977,.038981,
-.002072,.039948,
.004896,.039701,
.011716,.038247,
.01561,.03683,
.01939,.04061,
.012044,.04336,
.004331,.044793,
-.003513,.044864,
-.01125,.043573,
-.018645,.040957,
-.01939,.04061,
-.01561,.03683,
0.0*
%
%ADD34MACRO34*%
%AMMACRO25*
4,1,14,.02819,.01405,
.030201,.008941,
.031295,.003561,
.031438,-.001927,
.030626,-.007357,
.028883,-.012564,
.02819,-.01405,
.03189,-.01775,
.034488,-.011943,
.036038,-.005773,
.036493,.000573,
.035839,.006901,
.034096,.01302,
.03189,.01775,
.02819,.01405,
0.0*
4,1,14,.01405,-.02819,
.008941,-.030201,
.003561,-.031295,
-.001927,-.031438,
-.007357,-.030626,
-.012564,-.028883,
-.01405,-.02819,
-.01775,-.03189,
-.011943,-.034488,
-.005773,-.036038,
.000573,-.036493,
.006901,-.035839,
.01302,-.034096,
.01775,-.03189,
.01405,-.02819,
0.0*
4,1,14,-.02819,-.01405,
-.030201,-.008941,
-.031295,-.003561,
-.031438,.001927,
-.030626,.007357,
-.028883,.012564,
-.02819,.01405,
-.03189,.01775,
-.034488,.011943,
-.036038,.005773,
-.036493,-.000573,
-.035839,-.006901,
-.034096,-.01302,
-.03189,-.01775,
-.02819,-.01405,
0.0*
4,1,14,-.01405,.02819,
-.008941,.030201,
-.003561,.031295,
.001927,.031438,
.007357,.030626,
.012564,.028883,
.01405,.02819,
.01775,.03189,
.011943,.034488,
.005773,.036038,
-.000573,.036493,
-.006901,.035839,
-.01302,.034096,
-.01775,.03189,
-.01405,.02819,
0.0*
%
%ADD25MACRO25*%
%AMMACRO11*
4,1,14,.0575,.02922,
.0617,.018791,
.064026,.007792,
.064406,-.003445,
.06283,-.014576,
.059344,-.025265,
.0575,-.02922,
.06121,-.03292,
.065997,-.021791,
.068778,-.01,
.069469,.002095,
.06805,.014127,
.064563,.025729,
.06121,.03292,
.0575,.02922,
90.*
4,1,14,.02922,-.0575,
.018791,-.0617,
.007792,-.064026,
-.003445,-.064406,
-.014576,-.06283,
-.025265,-.059344,
-.02922,-.0575,
-.03292,-.06121,
-.021791,-.065997,
-.01,-.068778,
.002095,-.069469,
.014127,-.06805,
.025729,-.064563,
.03292,-.06121,
.02922,-.0575,
90.*
4,1,14,-.0575,-.02922,
-.0617,-.018791,
-.064026,-.007792,
-.064406,.003445,
-.06283,.014576,
-.059344,.025265,
-.0575,.02922,
-.06121,.03292,
-.065997,.021791,
-.068778,.01,
-.069469,-.002095,
-.06805,-.014127,
-.064563,-.025729,
-.06121,-.03292,
-.0575,-.02922,
90.*
4,1,14,-.02922,.0575,
-.018791,.0617,
-.007792,.064026,
.003445,.064406,
.014576,.06283,
.025265,.059344,
.02922,.0575,
.03292,.06121,
.021791,.065997,
.01,.068778,
-.002095,.069469,
-.014127,.06805,
-.025729,.064563,
-.03292,.06121,
-.02922,.0575,
90.*
%
%ADD11MACRO11*%
%AMMACRO40*
4,1,13,.02556,.01142,
.027155,.006808,
.027924,.001989,
.027846,-.00289,
.026921,-.007681,
.02556,-.01142,
.02931,-.01517,
.031499,-.00985,
.032731,-.004231,
.032968,.001517,
.032204,.007219,
.030461,.012702,
.02931,.01517,
.02556,.01142,
0.0*
4,1,13,.01142,-.02556,
.006808,-.027155,
.001989,-.027924,
-.00289,-.027846,
-.007681,-.026921,
-.01142,-.02556,
-.01517,-.02931,
-.00985,-.031499,
-.004231,-.032731,
.001517,-.032968,
.007219,-.032204,
.012702,-.030461,
.01517,-.02931,
.01142,-.02556,
0.0*
4,1,13,-.02556,-.01142,
-.027155,-.006808,
-.027924,-.001989,
-.027846,.00289,
-.026921,.007681,
-.02556,.01142,
-.02931,.01517,
-.031499,.00985,
-.032731,.004231,
-.032968,-.001517,
-.032204,-.007219,
-.030461,-.012702,
-.02931,-.01517,
-.02556,-.01142,
0.0*
4,1,13,-.01142,.02556,
-.006808,.027155,
-.001989,.027924,
.00289,.027846,
.007681,.026921,
.01142,.02556,
.01517,.02931,
.00985,.031499,
.004231,.032731,
-.001517,.032968,
-.007219,.032204,
-.012702,.030461,
-.01517,.02931,
-.01142,.02556,
0.0*
%
%ADD40MACRO40*%
%ADD48C,.02*%
%ADD49C,.006*%
%ADD61C,.06204*%
%ADD59C,.07204*%
%ADD58C,.06404*%
%ADD62C,.05604*%
%ADD60C,.05804*%
%ADD53C,.08504*%
%ADD52C,.08604*%
%ADD63C,.06904*%
%ADD50O,.21302X.15002*%
%ADD51O,.21304X.15004*%
%ADD54C,.15004*%
%ADD57C,.15204*%
%ADD56C,.11704*%
%ADD55C,.16204*%
G75*
%LPD*%
G75*
G36*
G01X-6000Y-6000D02*
X1406000D01*
Y1029622D01*
X-6000D01*
Y-6000D01*
G37*
%LPC*%
G75*
G36*
G01X1380315Y985185D02*
G02X1396996Y968504I0J-16681D01*
G01Y3937D01*
G02X1396063Y3004I-933J0D01*
G01X1210571D01*
G02X1209638Y3937I0J933D01*
G01Y171261D01*
G03X1209634Y171490I-6941J-7D01*
G01Y172503D01*
X1209500Y172637D01*
X1209488Y172695D01*
G03X1202697Y178201I-6791J-1435D01*
G02X1201764Y179134I0J933D01*
G01Y186750D01*
X1213311D01*
X1226250Y199689D01*
Y232811D01*
X1217811Y241250D01*
X1208996D01*
G03X1206004I-1496J-1750D01*
G01X1094689D01*
X1068129Y214689D01*
X1064250Y210811D01*
Y197811D01*
X1058689Y192250D01*
X1051689D01*
X1048750Y189311D01*
Y185189D01*
X1053689Y180250D01*
X1087811D01*
X1097811Y190250D01*
X1109142D01*
Y3937D01*
G02X1108209Y3004I-933J0D01*
G01X297047D01*
G02X296114Y3937I0J933D01*
G01Y62993D01*
G03X296110Y63222I-6941J-7D01*
G01Y64235D01*
X295976Y64368D01*
X295964Y64426D01*
G03X290607Y69783I-6791J-1434D01*
G01X290549Y69795D01*
X290416Y69929D01*
X289403D01*
G03X289174Y69933I-236J-6937D01*
G01X247835D01*
G02X246902Y70866I0J933D01*
G01Y224449D01*
G03X246898Y224678I-6941J-7D01*
G01Y225692D01*
X246764Y225826D01*
X246752Y225884D01*
G03X241396Y231240I-6791J-1435D01*
G01X241338Y231252D01*
X241204Y231386D01*
X240190D01*
G03X239961Y231390I-236J-6937D01*
G01X116142D01*
G02X111272Y236260I0J4870D01*
G01Y299252D01*
G03X111268Y299541I-10878J-6D01*
G01Y300495D01*
X111193Y300570D01*
X111184Y300638D01*
G03X101780Y310042I-10790J-1386D01*
G01X101712Y310051D01*
X101637Y310126D01*
X100683D01*
G03X100394Y310130I-295J-10874D01*
G01X11811D01*
G02X3004Y318937I0J8807D01*
G01Y968504D01*
G02X19685Y985185I16681J0D01*
G01X103741D01*
G03X103970Y985189I-7J6941D01*
G01X104983D01*
X105116Y985323D01*
X105174Y985335D01*
G03X110531Y990692I-1434J6791D01*
G01X110543Y990750D01*
X110677Y990883D01*
Y991896D01*
G03X110681Y992125I-6937J236D01*
G01Y1015106D01*
X133020D01*
Y994291D01*
G03X133024Y994065I6744J6D01*
G01Y993048D01*
X133162Y992910D01*
X133175Y992852D01*
G03X146353I6589J1439D01*
G01X146366Y992910D01*
X146504Y993048D01*
Y994065D01*
G03X146508Y994291I-6740J232D01*
G01Y1015106D01*
X184594D01*
Y992126D01*
G03X184598Y991897I6941J7D01*
G01Y990883D01*
X184732Y990749D01*
X184744Y990691D01*
G03X190100Y985335I6791J1435D01*
G01X190158Y985323D01*
X190292Y985189D01*
X191306D01*
G03X191535Y985185I236J6937D01*
G01X261221D01*
G03X261450Y985189I-7J6941D01*
G01X262463D01*
X262596Y985323D01*
X262654Y985335D01*
G03X268011Y990692I-1434J6791D01*
G01X268023Y990750D01*
X268157Y990883D01*
Y991896D01*
G03X268161Y992125I-6937J236D01*
G01Y1015106D01*
X542468D01*
Y994291D01*
G03X542472Y994065I6744J6D01*
G01Y993048D01*
X542610Y992910D01*
X542623Y992852D01*
G03X555802I6590J1439D01*
G01X555815Y992910D01*
X555953Y993048D01*
Y994065D01*
G03X555957Y994291I-6740J232D01*
G01Y1015106D01*
X594043D01*
Y992125D01*
G03X594047Y991896I6941J7D01*
G01Y990883D01*
X594181Y990749D01*
X594193Y990691D01*
G03X599549Y985335I6791J1435D01*
G01X599607Y985323D01*
X599741Y985189D01*
X600754D01*
G03X600983Y985185I236J6937D01*
G01X713190D01*
G03X713419Y985189I-7J6941D01*
G01X714432D01*
X714566Y985323D01*
X714624Y985335D01*
G03X719980Y990691I-1435J6791D01*
G01X719992Y990749D01*
X720126Y990883D01*
Y991896D01*
G03X720130Y992125I-6937J236D01*
G01Y1015106D01*
X742468D01*
Y994291D01*
G03X742472Y994065I6744J6D01*
G01Y993048D01*
X742610Y992910D01*
X742623Y992852D01*
G03X755802I6590J1439D01*
G01X755815Y992910D01*
X755953Y993048D01*
Y994065D01*
G03X755957Y994291I-6740J232D01*
G01Y1015106D01*
X794043D01*
Y992125D01*
G03X794047Y991896I6941J7D01*
G01Y990883D01*
X794181Y990749D01*
X794193Y990691D01*
G03X799549Y985335I6791J1435D01*
G01X799607Y985323D01*
X799741Y985189D01*
X800754D01*
G03X800983Y985185I236J6937D01*
G01X902165D01*
G02X918846Y968504I0J-16681D01*
G01Y775590D01*
G03X918850Y775361I6941J7D01*
G01Y774348D01*
X918984Y774215D01*
X918996Y774157D01*
G03X924353Y768800I6791J1434D01*
G01X924411Y768788D01*
X924544Y768654D01*
X925557D01*
G03X925786Y768650I236J6937D01*
G01X984844D01*
G03X985073Y768654I-7J6941D01*
G01X986086D01*
X986220Y768788D01*
X986278Y768800D01*
G03X991634Y774156I-1435J6791D01*
G01X991646Y774214D01*
X991780Y774348D01*
Y775361D01*
G03X991784Y775590I-6937J236D01*
G01Y968504D01*
G02X1008465Y985185I16681J0D01*
G01X1380315D01*
G37*
G36*
G01X1054311Y181750D02*
X1050250Y185811D01*
Y188689D01*
X1052311Y190750D01*
X1059311D01*
X1065750Y197189D01*
Y210189D01*
X1095311Y239750D01*
X1159193D01*
G03X1161807I1307J2250D01*
G01X1163693D01*
G03X1166307I1307J2250D01*
G01X1217189D01*
X1224750Y232189D01*
Y200311D01*
X1212689Y188250D01*
X1201764D01*
Y210631D01*
G03X1201760Y210863I-6941J-4D01*
G01Y211873D01*
X1201626Y212007D01*
X1201614Y212065D01*
G03X1196258Y217421I-6791J-1435D01*
G01X1196200Y217433D01*
X1196066Y217567D01*
X1195056D01*
G03X1194824Y217571I-236J-6937D01*
G01X1116082D01*
G03X1115850Y217567I4J-6941D01*
G01X1114840D01*
X1114707Y217433D01*
X1114649Y217421D01*
G03X1109292Y212064I1434J-6791D01*
G01X1109280Y212006D01*
X1109146Y211873D01*
Y210863D01*
G03X1109142Y210631I6937J-236D01*
G01Y191750D01*
X1097189D01*
X1087189Y181750D01*
X1054311D01*
G37*
%LPD*%
G75*
G36*
G01X1123260Y727579D02*
X1120812Y727928D01*
X1120781Y727923D01*
G02X1121211Y730936I-281J1577D01*
G01X1121240Y730921D01*
X1123688Y730572D01*
X1123720Y730577D01*
G02X1123289Y727564I280J-1577D01*
G01X1123260Y727579D01*
G37*
G36*
G01X1180141Y690540D02*
X1180172Y690530D01*
X1182283Y690559D01*
X1182314Y690570D01*
G02X1182354Y687726I503J-1415D01*
G01X1182323Y687736D01*
X1180212Y687707D01*
X1180181Y687696D01*
G02X1180141Y690540I-503J1415D01*
G37*
G36*
G01X1192392Y682405D02*
X1192363Y682415D01*
X1190322Y682510D01*
X1190293Y682502D01*
G02X1190435Y685559I-403J1551D01*
G01X1190464Y685549D01*
X1192505Y685454D01*
X1192534Y685462D01*
G02X1192392Y682405I403J-1551D01*
G37*
G36*
G01X1379639Y609381D02*
G03Y608848I298J-266D01*
G02X1376353I-1643J-1466D01*
G03Y609381I-298J267D01*
G02X1379639I1643J1466D01*
G37*
G36*
G01X1382336Y600343D02*
Y600007D01*
X1382402Y599948D01*
G02X1379448I-1477J-1633D01*
G01X1379514Y600007D01*
Y600343D01*
X1379448Y600402D01*
G02X1382402I1477J1633D01*
G01X1382336Y600343D01*
G37*
G36*
G01X1383443Y579784D02*
X1383107D01*
X1383048Y579718D01*
G02Y582672I-1633J1477D01*
G01X1383107Y582606D01*
X1383443D01*
X1383502Y582672D01*
G02Y579718I1633J-1477D01*
G01X1383443Y579784D01*
G37*
G36*
G01X469326Y408344D02*
Y405437D01*
X469336Y405405D01*
G02X466492I-1422J-483D01*
G01X466502Y405437D01*
Y408344D01*
X466492Y408376D01*
G02X469336I1422J483D01*
G01X469326Y408344D01*
G37*
G36*
G01X465388D02*
Y405437D01*
X465399Y405405D01*
G02X462555I-1422J-483D01*
G01X462566Y405437D01*
Y408344D01*
X462555Y408376D01*
G02X465399I1422J483D01*
G01X465388Y408344D01*
G37*
G36*
G01X449638D02*
Y405437D01*
X449649Y405405D01*
G02X446805I-1422J-483D01*
G01X446816Y405437D01*
Y408344D01*
X446805Y408376D01*
G02X449649I1422J483D01*
G01X449638Y408344D01*
G37*
G36*
G01X445702D02*
Y405437D01*
X445712Y405405D01*
G02X442868I-1422J-483D01*
G01X442878Y405437D01*
Y408344D01*
X442868Y408376D01*
G02X445712I1422J483D01*
G01X445702Y408344D01*
G37*
G36*
G01X441764D02*
Y405437D01*
X441775Y405405D01*
G02X438931I-1422J-483D01*
G01X438942Y405437D01*
Y408344D01*
X438931Y408376D01*
G02X441775I1422J483D01*
G01X441764Y408344D01*
G37*
G36*
G01X437828D02*
Y405437D01*
X437838Y405405D01*
G02X434994I-1422J-483D01*
G01X435004Y405437D01*
Y408344D01*
X434994Y408376D01*
G02X437838I1422J483D01*
G01X437828Y408344D01*
G37*
G36*
G01X433890D02*
Y405437D01*
X433901Y405405D01*
G02X431057I-1422J-483D01*
G01X431068Y405437D01*
Y408344D01*
X431057Y408376D01*
G02X433901I1422J483D01*
G01X433890Y408344D01*
G37*
G36*
G01X429954D02*
Y405437D01*
X429964Y405405D01*
G02X427120I-1422J-483D01*
G01X427130Y405437D01*
Y408344D01*
X427120Y408376D01*
G02X429964I1422J483D01*
G01X429954Y408344D01*
G37*
G36*
G01X426016D02*
Y405437D01*
X426027Y405405D01*
G02X423183I-1422J-483D01*
G01X423194Y405437D01*
Y408344D01*
X423183Y408376D01*
G02X426027I1422J483D01*
G01X426016Y408344D01*
G37*
G36*
G01X422080D02*
Y405437D01*
X422090Y405405D01*
G02X419246I-1422J-483D01*
G01X419256Y405437D01*
Y408344D01*
X419246Y408376D01*
G02X422090I1422J483D01*
G01X422080Y408344D01*
G37*
G36*
G01X457634Y408268D02*
Y405398D01*
X457645Y405366D01*
G02X454801I-1422J-483D01*
G01X454812Y405398D01*
Y408268D01*
X454801Y408300D01*
G02X457645I1422J483D01*
G01X457634Y408268D01*
G37*
G36*
G01X453634D02*
Y405398D01*
X453645Y405366D01*
G02X450801I-1422J-483D01*
G01X450812Y405398D01*
Y408268D01*
X450801Y408300D01*
G02X453645I1422J483D01*
G01X453634Y408268D01*
G37*
G36*
G01X74347Y386464D02*
X73619D01*
G02Y389488I-1736J1512D01*
G01X74347D01*
G02Y386464I1736J-1512D01*
G37*
G36*
G01X64795Y386309D02*
X64553Y386302D01*
X64496Y386238D01*
G02X64410Y389404I-1713J1538D01*
G01X64471Y389343D01*
X64713Y389350D01*
X64770Y389414D01*
G02X64856Y386248I1713J-1538D01*
G01X64795Y386309D01*
G37*
G36*
G01X45413Y389489D02*
G03X45946Y389490I266J299D01*
G02X45953Y386056I1537J-1714D01*
G03X45420Y386055I-266J-299D01*
G02X45413Y389489I-1537J1714D01*
G37*
G36*
G01X55229Y386273D02*
X55000Y386260D01*
X54945Y386194D01*
G02X54774Y389339I-1762J1481D01*
G01X54837Y389279D01*
X55066Y389292D01*
X55122Y389358D01*
G02X55291Y386213I1761J-1482D01*
G01X55229Y386273D01*
G37*
G36*
G01X484136Y370835D02*
X484168Y370825D01*
X487061Y370884D01*
X487092Y370895D01*
G02X487150Y368051I511J-1412D01*
G01X487118Y368061D01*
X484225Y368002D01*
X484194Y367991D01*
G02X484136Y370835I-511J1412D01*
G37*
G36*
G01X485085Y364979D02*
X485074Y364948D01*
Y362127D01*
X485084Y362096D01*
G02X482240Y362097I-1422J-483D01*
G01X482251Y362128D01*
Y364949D01*
X482241Y364980D01*
G02X485085Y364979I1422J483D01*
G37*
G36*
G01X522012Y361968D02*
Y359469D01*
X522022Y359438D01*
G02X518978I-1522J-501D01*
G01X518988Y359469D01*
Y361968D01*
X518978Y361999D01*
G02X522022I1522J501D01*
G01X522012Y361968D01*
G37*
G36*
G01X487084Y356264D02*
X484177D01*
X484145Y356254D01*
G02Y359098I-483J1422D01*
G01X484177Y359088D01*
X487084D01*
X487116Y359098D01*
G02Y356254I483J-1422D01*
G01X487084Y356264D01*
G37*
G36*
G01X164909Y353198D02*
X164539D01*
X164480Y353134D01*
G02Y356284I-1679J1575D01*
G01X164539Y356220D01*
X164909D01*
X164968Y356284D01*
G02Y353134I1679J-1575D01*
G01X164909Y353198D01*
G37*
G36*
G01X153409D02*
X153039D01*
X152980Y353134D01*
G02Y356284I-1679J1575D01*
G01X153039Y356220D01*
X153409D01*
X153468Y356284D01*
G02Y353134I1679J-1575D01*
G01X153409Y353198D01*
G37*
G36*
G01X141409D02*
X141039D01*
X140980Y353134D01*
G02Y356284I-1679J1575D01*
G01X141039Y356220D01*
X141409D01*
X141468Y356284D01*
G02Y353134I1679J-1575D01*
G01X141409Y353198D01*
G37*
G36*
G01X129409D02*
X129039D01*
X128980Y353134D01*
G02Y356284I-1679J1575D01*
G01X129039Y356220D01*
X129409D01*
X129468Y356284D01*
G02Y353134I1679J-1575D01*
G01X129409Y353198D01*
G37*
G36*
G01X487084Y352328D02*
X484177D01*
X484145Y352317D01*
G02Y355161I-483J1422D01*
G01X484177Y355150D01*
X487084D01*
X487116Y355161D01*
G02Y352317I483J-1422D01*
G01X487084Y352328D01*
G37*
G36*
G01X528012Y356000D02*
Y353501D01*
X528022Y353470D01*
G02X524978I-1522J-501D01*
G01X524988Y353501D01*
Y356000D01*
X524978Y356031D01*
G02X528022I1522J501D01*
G01X528012Y356000D01*
G37*
G36*
G01X522012Y350968D02*
Y348469D01*
X522022Y348438D01*
G02X518978I-1522J-501D01*
G01X518988Y348469D01*
Y350968D01*
X518978Y350999D01*
G02X522022I1522J501D01*
G01X522012Y350968D01*
G37*
G36*
G01X1198147Y342875D02*
G03X1197613I-267J-298D01*
G02Y346301I-1538J1713D01*
G03X1198147I267J298D01*
G02Y342875I1538J-1713D01*
G37*
G36*
G01X528012Y346000D02*
Y343501D01*
X528022Y343470D01*
G02X524978I-1522J-501D01*
G01X524988Y343501D01*
Y346000D01*
X524978Y346031D01*
G02X528022I1522J501D01*
G01X528012Y346000D01*
G37*
G36*
G01X194386Y343719D02*
Y343349D01*
X194449Y343290D01*
G02X191299I-1575J-1679D01*
G01X191362Y343349D01*
Y343719D01*
X191299Y343778D01*
G02X194449I1575J1679D01*
G01X194386Y343719D01*
G37*
G36*
G01X1320223Y336660D02*
X1320213Y336726D01*
X1318750Y338189D01*
Y373811D01*
X1321689Y376750D01*
X1340311D01*
X1343250Y373811D01*
Y346718D01*
G02Y343028I-1377J-1845D01*
G01Y339189D01*
X1339811Y335750D01*
X1324433D01*
G02X1320223Y336660I-1933J1250D01*
G37*
G36*
G01X486937Y332441D02*
X486906Y332453D01*
X484094Y332615D01*
X484062Y332606D01*
G02X484225Y335446I-400J1448D01*
G01X484256Y335434D01*
X487068Y335272D01*
X487100Y335281D01*
G02X486937Y332441I400J-1448D01*
G37*
G36*
G01X487084Y328706D02*
X484177D01*
X484145Y328695D01*
G02Y331539I-483J1422D01*
G01X484177Y331528D01*
X487084D01*
X487116Y331539D01*
G02Y328695I483J-1422D01*
G01X487084Y328706D01*
G37*
G36*
G01X194386Y332569D02*
Y332199D01*
X194449Y332140D01*
G02X191299I-1575J-1679D01*
G01X191362Y332199D01*
Y332569D01*
X191299Y332628D01*
G02X194449I1575J1679D01*
G01X194386Y332569D01*
G37*
G36*
G01X177884Y327238D02*
X177514D01*
X177455Y327174D01*
G02Y330324I-1679J1575D01*
G01X177514Y330260D01*
X177884D01*
X177943Y330324D01*
G02Y327174I1679J-1575D01*
G01X177884Y327238D01*
G37*
G36*
G01X166255Y327188D02*
X165885D01*
X165826Y327124D01*
G02Y330274I-1679J1575D01*
G01X165885Y330210D01*
X166255D01*
X166314Y330274D01*
G02Y327124I1679J-1575D01*
G01X166255Y327188D01*
G37*
G36*
G01X487084Y324768D02*
X484177D01*
X484145Y324758D01*
G02Y327602I-483J1422D01*
G01X484177Y327592D01*
X487084D01*
X487116Y327602D01*
G02Y324758I483J-1422D01*
G01X487084Y324768D01*
G37*
G36*
G01X532970Y323988D02*
X530380D01*
X530349Y323978D01*
G02Y327022I-501J1522D01*
G01X530380Y327012D01*
X532970D01*
X533001Y327022D01*
G02Y323978I501J-1522D01*
G01X532970Y323988D01*
G37*
G36*
G01X1171587Y322003D02*
G03X1171053I-267J-298D01*
G02Y325429I-1538J1713D01*
G03X1171587I267J298D01*
G02Y322003I1538J-1713D01*
G37*
G36*
G01X157386Y325219D02*
Y324849D01*
X157449Y324790D01*
G02X154299I-1575J-1679D01*
G01X154362Y324849D01*
Y325219D01*
X154299Y325278D01*
G02X157449I1575J1679D01*
G01X157386Y325219D01*
G37*
G36*
G01X538082Y319488D02*
X535492D01*
X535461Y319478D01*
G02Y322522I-501J1522D01*
G01X535492Y322512D01*
X538082D01*
X538113Y322522D01*
G02Y319478I501J-1522D01*
G01X538082Y319488D01*
G37*
G36*
G01X511468Y318488D02*
X509032D01*
X509001Y318478D01*
G02Y321522I-501J1522D01*
G01X509032Y321512D01*
X511468D01*
X511499Y321522D01*
G02Y318478I501J-1522D01*
G01X511468Y318488D01*
G37*
G36*
G01X1254788Y322854D02*
Y322146D01*
X1254844Y322088D01*
G02X1251510I-1667J-1588D01*
G01X1251566Y322146D01*
Y322854D01*
X1251510Y322912D01*
G02X1254844I1667J1588D01*
G01X1254788Y322854D01*
G37*
G36*
G01X526470Y317848D02*
X523880D01*
X523849Y317837D01*
G02Y320881I-501J1522D01*
G01X523880Y320870D01*
X526470D01*
X526501Y320881D01*
G02Y317837I501J-1522D01*
G01X526470Y317848D01*
G37*
G36*
G01X494571Y314440D02*
X491789D01*
X491758Y314430D01*
G02Y317474I-501J1522D01*
G01X491789Y317464D01*
X494571D01*
X494602Y317474D01*
G02Y314430I501J-1522D01*
G01X494571Y314440D01*
G37*
G36*
G01X502715Y312688D02*
X502345D01*
X502286Y312625D01*
G02Y315775I-1679J1575D01*
G01X502345Y315712D01*
X502715D01*
X502774Y315775D01*
G02Y312625I1679J-1575D01*
G01X502715Y312688D01*
G37*
G36*
G01X517968Y312488D02*
X517598D01*
X517539Y312425D01*
G02Y315575I-1679J1575D01*
G01X517598Y315512D01*
X517968D01*
X518027Y315575D01*
G02Y312425I1679J-1575D01*
G01X517968Y312488D01*
G37*
G36*
G01X157386Y316069D02*
Y315699D01*
X157449Y315640D01*
G02X154299I-1575J-1679D01*
G01X154362Y315699D01*
Y316069D01*
X154299Y316128D01*
G02X157449I1575J1679D01*
G01X157386Y316069D01*
G37*
G36*
G01X1157813Y314867D02*
G03Y314333I298J-267D01*
G02X1154387I-1713J-1538D01*
G03Y314867I-298J267D01*
G02X1157813I1713J1538D01*
G37*
G36*
G01X1251863Y310336D02*
X1251916Y310395D01*
X1251897Y311124D01*
X1251842Y311180D01*
G02X1255191Y311264I1635J1620D01*
G01X1255138Y311205D01*
X1255157Y310476D01*
X1255212Y310420D01*
G02X1251863Y310336I-1635J-1620D01*
G37*
G36*
G01X1166713Y306637D02*
G03Y306103I298J-267D01*
G02X1163287I-1713J-1538D01*
G03Y306637I-298J267D01*
G02X1166713I1713J1538D01*
G37*
G36*
G01X805070Y301738D02*
X804680D01*
X804621Y301675D01*
G02Y304825I-1679J1575D01*
G01X804680Y304762D01*
X805070D01*
X805129Y304825D01*
G02Y301675I1679J-1575D01*
G01X805070Y301738D01*
G37*
G36*
G01X789320D02*
X788930D01*
X788871Y301675D01*
G02Y304825I-1679J1575D01*
G01X788930Y304762D01*
X789320D01*
X789379Y304825D01*
G02Y301675I1679J-1575D01*
G01X789320Y301738D01*
G37*
G36*
G01X773575D02*
X773185D01*
X773126Y301675D01*
G02Y304825I-1679J1575D01*
G01X773185Y304762D01*
X773575D01*
X773634Y304825D01*
G02Y301675I1679J-1575D01*
G01X773575Y301738D01*
G37*
G36*
G01X757825D02*
X757435D01*
X757376Y301675D01*
G02Y304825I-1679J1575D01*
G01X757435Y304762D01*
X757825D01*
X757884Y304825D01*
G02Y301675I1679J-1575D01*
G01X757825Y301738D01*
G37*
G36*
G01X663335D02*
X662945D01*
X662886Y301675D01*
G02Y304825I-1679J1575D01*
G01X662945Y304762D01*
X663335D01*
X663394Y304825D01*
G02Y301675I1679J-1575D01*
G01X663335Y301738D01*
G37*
G36*
G01X647585D02*
X647195D01*
X647136Y301675D01*
G02Y304825I-1679J1575D01*
G01X647195Y304762D01*
X647585D01*
X647644Y304825D01*
G02Y301675I1679J-1575D01*
G01X647585Y301738D01*
G37*
G36*
G01X631840D02*
X631450D01*
X631391Y301675D01*
G02Y304825I-1679J1575D01*
G01X631450Y304762D01*
X631840D01*
X631899Y304825D01*
G02Y301675I1679J-1575D01*
G01X631840Y301738D01*
G37*
G36*
G01X616090D02*
X615700D01*
X615641Y301675D01*
G02Y304825I-1679J1575D01*
G01X615700Y304762D01*
X616090D01*
X616149Y304825D01*
G02Y301675I1679J-1575D01*
G01X616090Y301738D01*
G37*
G36*
G01X1262188Y298322D02*
Y297748D01*
X1262244Y297690D01*
G02X1258910I-1667J-1588D01*
G01X1258966Y297748D01*
Y298322D01*
X1258910Y298380D01*
G02X1262244I1667J1588D01*
G01X1262188Y298322D01*
G37*
G36*
G01X211995Y293398D02*
X211625D01*
X211566Y293334D01*
G02Y296484I-1679J1575D01*
G01X211625Y296420D01*
X211995D01*
X212054Y296484D01*
G02Y293334I1679J-1575D01*
G01X211995Y293398D01*
G37*
G36*
G01X202547D02*
X202177D01*
X202118Y293334D01*
G02Y296484I-1679J1575D01*
G01X202177Y296420D01*
X202547D01*
X202606Y296484D01*
G02Y293334I1679J-1575D01*
G01X202547Y293398D01*
G37*
G36*
G01X177350D02*
X176980D01*
X176921Y293334D01*
G02Y296484I-1679J1575D01*
G01X176980Y296420D01*
X177350D01*
X177409Y296484D01*
G02Y293334I1679J-1575D01*
G01X177350Y293398D01*
G37*
G36*
G01X167901Y292798D02*
X167531D01*
X167472Y292734D01*
G02Y295884I-1679J1575D01*
G01X167531Y295820D01*
X167901D01*
X167960Y295884D01*
G02Y292734I1679J-1575D01*
G01X167901Y292798D01*
G37*
G36*
G01X1172039Y288614D02*
X1171515D01*
X1171456Y288550D01*
G02Y291700I-1679J1575D01*
G01X1171515Y291636D01*
X1172039D01*
X1172098Y291700D01*
G02Y288550I1679J-1575D01*
G01X1172039Y288614D01*
G37*
G36*
G01X1191005Y288288D02*
X1190615D01*
X1190556Y288225D01*
G02Y291375I-1679J1575D01*
G01X1190615Y291312D01*
X1191005D01*
X1191064Y291375D01*
G02Y288225I1679J-1575D01*
G01X1191005Y288288D01*
G37*
G36*
G01X417366Y423246D02*
X417250Y423192D01*
Y422085D01*
X417366Y422031D01*
G02Y419309I-635J-1361D01*
G01X417250Y419255D01*
Y418148D01*
X417366Y418094D01*
G02Y415372I-635J-1361D01*
G01X417250Y415318D01*
Y414211D01*
X417366Y414157D01*
G02Y411435I-635J-1361D01*
G01X417250Y411381D01*
Y406337D01*
X417366Y406283D01*
G02X417874Y403947I-635J-1361D01*
G03X417885Y403676I152J-130D01*
G01X427496Y394065D01*
G02X429737Y392073I1059J-1065D01*
G01X429627Y391934D01*
X435750Y385811D01*
Y359660D01*
G03X436203Y359264I400J0D01*
G02X437759Y356802I213J-1588D01*
G01X439547Y355014D01*
X439676Y355080D01*
G02X441694Y353062I677J-1341D01*
G01X441628Y352933D01*
X443484Y351077D01*
X443613Y351143D01*
G02X445679Y350374I677J-1341D01*
G01X445730Y350250D01*
X446787D01*
X446838Y350374D01*
G02X449616I1389J-572D01*
G01X449667Y350250D01*
X450881D01*
G02X453449I1284J-780D01*
G01X454374D01*
X454423Y350378D01*
G02X457227I1402J-538D01*
G01X457276Y350250D01*
X458600D01*
X458651Y350374D01*
G02X461429I1389J-572D01*
G01X461480Y350250D01*
X462435D01*
X462488Y350367D01*
G02X465402I1457J-667D01*
G01X465455Y350250D01*
X467311D01*
X473250Y344311D01*
Y338539D01*
X473262Y338506D01*
G02Y337476I-1411J-515D01*
G01X473250Y337443D01*
Y326728D01*
X473262Y326695D01*
G02Y325665I-1411J-515D01*
G01X473250Y325632D01*
Y322791D01*
X473262Y322758D01*
G02Y321728I-1411J-515D01*
G01X473250Y321695D01*
Y308689D01*
X455311Y290750D01*
X419942D01*
X419922Y290746D01*
G02X418988I-467J2254D01*
G01X418968Y290750D01*
X418311D01*
X414311Y286750D01*
X326689D01*
X285995Y327444D01*
X285895Y327428D01*
G02X282928Y330395I-395J2572D01*
G01X282944Y330495D01*
X228750Y384689D01*
Y424189D01*
X226689Y426250D01*
X187189D01*
X115250Y498189D01*
Y595311D01*
X122189Y602250D01*
X273311D01*
X339425Y536136D01*
X339566Y536255D01*
G02X342686Y532875I1489J-1756D01*
G01X344383Y531178D01*
X344444Y531167D01*
G02X346222Y529389I-389J-2167D01*
G01X346233Y529328D01*
X417250Y458311D01*
Y426022D01*
X417366Y425968D01*
G02Y423246I-635J-1361D01*
G37*
G36*
G01X1252288Y285854D02*
Y285146D01*
X1252344Y285088D01*
G02X1249010I-1667J-1588D01*
G01X1249066Y285146D01*
Y285854D01*
X1249010Y285912D01*
G02X1252344I1667J1588D01*
G01X1252288Y285854D01*
G37*
G36*
G01X1256456Y270695D02*
Y270305D01*
X1256519Y270246D01*
G02X1253369I-1575J-1679D01*
G01X1253432Y270305D01*
Y270695D01*
X1253369Y270754D01*
G02X1256519I1575J1679D01*
G01X1256456Y270695D01*
G37*
G36*
G01X309166Y162288D02*
X306384D01*
X306353Y162278D01*
G02Y165322I-501J1522D01*
G01X306384Y165312D01*
X309166D01*
X309197Y165322D01*
G02Y162278I501J-1522D01*
G01X309166Y162288D01*
G37*
G36*
G01X316716Y154488D02*
X313934D01*
X313903Y154478D01*
G02Y157522I-501J1522D01*
G01X313934Y157512D01*
X316716D01*
X316747Y157522D01*
G02Y154478I501J-1522D01*
G01X316716Y154488D01*
G37*
G36*
G01X327934Y151975D02*
Y149476D01*
X327944Y149445D01*
G02X324900I-1522J-501D01*
G01X324910Y149476D01*
Y151975D01*
X324900Y152006D01*
G02X327944I1522J501D01*
G01X327934Y151975D01*
G37*
G36*
G01X329512Y149097D02*
X329522Y149127D01*
X329606Y152153D01*
X329597Y152183D01*
G02X332457Y152104I1443J418D01*
G01X332447Y152074D01*
X332363Y149048D01*
X332372Y149018D01*
G02X329512Y149097I-1443J-418D01*
G37*
G36*
G01X303145Y142816D02*
X301567D01*
G02Y145840I-1736J1512D01*
G01X303145D01*
X303176Y145850D01*
G02Y142806I501J-1522D01*
G01X303145Y142816D01*
G37*
G36*
G01X321312Y146366D02*
Y143584D01*
X321322Y143553D01*
G02X318278I-1522J-501D01*
G01X318288Y143584D01*
Y146366D01*
X318278Y146397D01*
G02X321322I1522J501D01*
G01X321312Y146366D01*
G37*
G36*
G01X328612Y139325D02*
Y136826D01*
X328622Y136795D01*
G02X325578I-1522J-501D01*
G01X325588Y136826D01*
Y139325D01*
X325578Y139356D01*
G02X328622I1522J501D01*
G01X328612Y139325D01*
G37*
G36*
G01X336112Y132499D02*
Y130000D01*
X336122Y129969D01*
G02X333078I-1522J-501D01*
G01X333088Y130000D01*
Y132499D01*
X333078Y132530D01*
G02X336122I1522J501D01*
G01X336112Y132499D01*
G37*
G36*
G01X1092156Y124988D02*
X1091766D01*
X1091707Y124925D01*
G02Y128075I-1679J1575D01*
G01X1091766Y128012D01*
X1092156D01*
X1092215Y128075D01*
G02Y124925I1679J-1575D01*
G01X1092156Y124988D01*
G37*
G36*
G01X1072448Y40156D02*
X1069284D01*
G02Y46378I-2355J3111D01*
G01X1072448D01*
G02Y40156I2355J-3111D01*
G37*
G36*
G01X488233Y320083D02*
G02X487071Y317098I-621J-1477D01*
G01X487040Y317109D01*
X484435Y317176D01*
X484403Y317166D01*
G02X483299Y319951I-448J1434D01*
G03X483309Y320666I-174J360D01*
G02X484502Y323416I691J1334D01*
G01X484532Y323405D01*
X486713Y323336D01*
X486743Y323344D01*
G02X488128Y320756I412J-1444D01*
G03X488233Y320083I260J-304D01*
G37*
G36*
G01X369741Y151443D02*
X369744Y149343D01*
X369755Y149312D01*
G02X369398Y147768I-1422J-485D01*
G03X369680Y147086I284J-282D01*
G01X370984Y147081D01*
X371016Y147091D01*
G02X372867Y146274I477J-1424D01*
G01X372920Y146154D01*
X373250D01*
Y146311D01*
X376466Y149527D01*
G02X377049Y150120I1321J-715D01*
G01X377072Y150133D01*
X377189Y150250D01*
X377352D01*
X377379Y150258D01*
G02X378195I408J-1446D01*
G01X378222Y150250D01*
X380499D01*
X380523Y150256D01*
G02X381253I365J-1457D01*
G01X381277Y150250D01*
X405718D01*
X405743Y150257D01*
G02X406507I382J-1453D01*
G01X406532Y150250D01*
X412045D01*
X412068Y150255D01*
G02X412762I347J-1461D01*
G01X412785Y150250D01*
X413189D01*
X414219Y151280D01*
X414166Y151404D01*
G02X416135Y153373I1383J586D01*
G01X416259Y153320D01*
X423661Y160722D01*
X423610Y160845D01*
G02X425570Y162805I1389J571D01*
G01X425693Y162754D01*
X426810Y163871D01*
X426760Y163994D01*
G02X428720Y165954I1389J571D01*
G01X428843Y165904D01*
X436260Y173321D01*
X436209Y173444D01*
G02X438169Y175404I1389J571D01*
G01X438292Y175353D01*
X442549Y179610D01*
X442496Y179734D01*
G02X444465Y181703I1383J586D01*
G01X444589Y181650D01*
X445189Y182250D01*
X471311D01*
X485750Y167811D01*
Y118311D01*
X487699Y116362D01*
X487815Y116398D01*
G02X489547Y116250I685J-2198D01*
G01X521213D01*
X521233Y116254D01*
G02X522167I467J-2254D01*
G01X522187Y116250D01*
X535190D01*
X566310Y147254D01*
X566303Y147345D01*
G02X568663Y149696I2197J155D01*
G01X568754Y149689D01*
X668970Y249531D01*
X669189Y249750D01*
X669190D01*
X669191Y249751D01*
X669501Y249750D01*
X947311D01*
X953750Y243311D01*
Y214689D01*
X947811Y208750D01*
X748933D01*
G02X745067I-1933J1250D01*
G01X692811D01*
X549311Y65250D01*
X422189D01*
X373250Y114189D01*
Y135574D01*
X373233Y135612D01*
G02X373216Y135652I1374J607D01*
G03X372846I-185J-76D01*
G02X370962Y134803I-1390J569D01*
G01X370930Y134814D01*
X368799Y134830D01*
X368768Y134820D01*
G02X367460Y137494I-472J1426D01*
G03X367462Y138158I-222J333D01*
G02X366884Y139888I843J1243D01*
G01X366895Y139920D01*
X366901Y141995D01*
X366890Y142026D01*
G02X367487Y143759I1424J479D01*
G03Y144426I-221J334D01*
G02X367478Y146928I827J1254D01*
G03X367482Y147589I-223J332D01*
G02X366910Y149308I851J1238D01*
G01X366921Y149340D01*
X366918Y151440D01*
X366907Y151471D01*
G02X367260Y153011I1422J485D01*
G03X366975Y153693I-284J282D01*
G01X365658Y153690D01*
X365626Y153679D01*
G02X365620Y156523I-486J1421D01*
G01X365651Y156513D01*
X366935Y156515D01*
G03X367215Y157200I-1J400D01*
G02X366857Y158776I1056J1068D01*
G01X366869Y158807D01*
X366905Y160911D01*
X366895Y160942D01*
G02X367276Y162474I1431J458D01*
G03X366993Y163160I-279J286D01*
G01X365686Y163148D01*
X365655Y163137D01*
G02X365627Y165981I-497J1417D01*
G01X365659Y165971D01*
X366971Y165983D01*
G03X367255Y166661I-4J400D01*
G02X366908Y168178I1079J1045D01*
G01X366918Y168209D01*
X366902Y170304D01*
X366891Y170336D01*
G02X369735Y170358I1418J494D01*
G01X369725Y170327D01*
X369741Y168232D01*
X369752Y168201D01*
G02X369189Y166471I-1418J-495D01*
G03X369187Y165815I228J-329D01*
G02X369147Y163328I-862J-1230D01*
G03Y162658I218J-335D01*
G02X369740Y160892I-821J-1258D01*
G01X369728Y160861D01*
X369692Y158757D01*
X369702Y158726D01*
G02X369131Y157036I-1431J-458D01*
G03X369144Y156372I229J-328D01*
G02X369173Y153862I-811J-1265D01*
G03X369172Y153199I223J-332D01*
G02X369752Y151475I-843J-1243D01*
G01X369741Y151443D01*
G37*
G54D61*
X1272441Y7087D03*
X1299213D03*
G54D59*
X1224016Y180709D03*
G54D58*
X945197Y380000D03*
X968819D03*
G54D62*
X1379862Y108465D03*
Y119095D03*
G54D60*
X1224016Y386221D03*
G54D53*
X35435Y373228D03*
X82675D03*
G54D52*
X21220D03*
X96890D03*
X157480Y283071D03*
X220472D03*
G54D63*
X402953Y23622D03*
X413189D03*
X423425D03*
G54D50*
X1227165Y411417D03*
X1227166Y155511D03*
X1008268Y411417D03*
G54D51*
Y244094D03*
G54D54*
X270078Y92125D03*
Y155117D03*
X743897Y353543D03*
Y410629D03*
X1305117Y87548D03*
Y262745D03*
X1376968Y147243D03*
Y216535D03*
X490944Y255118D03*
G54D57*
X600925Y44134D03*
X638917D03*
G54D56*
X537994Y303150D03*
X825984D03*
G54D55*
X355708Y96456D03*
X450196Y257874D03*
X572243Y337992D03*
%LPC*%
G75*
G36*
G01X471750Y323751D02*
X471585Y323721D01*
G03Y320765I266J-1478D01*
G01X471750Y320735D01*
Y309311D01*
X454689Y292250D01*
X417689D01*
X413689Y288250D01*
X362987D01*
X362967Y288254D01*
G03X362033I-467J-2254D01*
G01X362013Y288250D01*
X327311D01*
X287375Y328186D01*
X287493Y328327D01*
G03X283691Y331870I-1993J1673D01*
G01X230250Y385311D01*
Y424811D01*
X227311Y427750D01*
X187811D01*
X116750Y498811D01*
Y594689D01*
X122811Y600750D01*
X272689D01*
X338758Y534681D01*
X338755Y534593D01*
G03X341148Y532200I2300J-93D01*
G01X341236Y532203D01*
X349834Y523605D01*
X349846Y523548D01*
G03X351603Y521791I2249J492D01*
G01X351660Y521779D01*
X361777Y511662D01*
X361788Y511600D01*
G03X363655Y509733I2267J400D01*
G01X363717Y509722D01*
X415750Y457689D01*
Y425744D01*
G03Y423470I981J-1137D01*
G01Y421807D01*
G03Y419533I981J-1137D01*
G01Y417870D01*
G03Y415596I981J-1137D01*
G01Y413933D01*
G03Y411659I981J-1137D01*
G01Y406059D01*
G03X415689Y403840I981J-1137D01*
G01X415750Y403781D01*
Y403689D01*
X418677Y400762D01*
X418687Y400696D01*
G03X420379Y399004I1981J289D01*
G01X420445Y398994D01*
X427404Y392035D01*
G03X427590Y391849I1151J965D01*
G01X430488Y388951D01*
X430498Y388885D01*
G03X432190Y387193I1981J289D01*
G01X432256Y387183D01*
X434250Y385189D01*
Y358189D01*
X434813Y357626D01*
X434819Y357552D01*
G03X436292Y356079I1597J124D01*
G01X436366Y356073D01*
X438858Y353581D01*
X438868Y353516D01*
G03X440130Y352254I1485J223D01*
G01X440195Y352244D01*
X442795Y349644D01*
X442805Y349579D01*
G03X445362Y348750I1485J223D01*
G01X447155D01*
G03X449299I1072J1052D01*
G01X450847D01*
G03X453483I1318J720D01*
G01X454792D01*
G03X456858I1033J1090D01*
G01X458968D01*
G03X461112I1072J1052D01*
G01X462655D01*
G03X465235I1290J950D01*
G01X466211D01*
G03X467556Y347832I1704J1052D01*
G01X467618Y347821D01*
X471750Y343689D01*
Y339499D01*
X471585Y339469D01*
G03Y336513I266J-1478D01*
G01X471750Y336483D01*
Y327688D01*
X471585Y327658D01*
G03Y324702I266J-1478D01*
G01X471750Y324672D01*
Y323751D01*
G37*
G36*
G01X375434Y137474D02*
G02X375433Y138140I221J333D01*
G03X375846Y138552I-834J1249D01*
G02X376509Y138554I332J-223D01*
G03X379173Y139878I1240J847D01*
G01X379163Y139909D01*
X379167Y142002D01*
X379178Y142034D01*
G03X376513Y143362I-1421J486D01*
G02X375851I-331J224D01*
G03X374910Y143991I-1244J-842D01*
G01X374750Y144024D01*
Y145689D01*
X376769Y147708D01*
G03X379008Y147937I1018J1104D01*
G02X379660Y147934I325J-233D01*
G03X382374Y148579I1228J865D01*
G01X382399Y148750D01*
X404614D01*
X404640Y148580D01*
G03X407610I1485J224D01*
G01X407636Y148750D01*
X409189D01*
X410750Y147189D01*
Y139189D01*
X414098Y135841D01*
X414112Y135792D01*
G03X415123Y134781I1440J429D01*
G01X415172Y134767D01*
X420449Y129490D01*
X420354Y129353D01*
G03X422443Y127264I1236J-853D01*
G01X422581Y127358D01*
X435189Y114750D01*
X535499D01*
X535809Y114749D01*
X535810Y114750D01*
X535811D01*
X536030Y114969D01*
X567029Y145852D01*
X567168Y145747D01*
G03X570258Y148826I1332J1753D01*
G01X570153Y148965D01*
X669810Y248250D01*
X778663D01*
G03X781337I1337J1750D01*
G01X946689D01*
X952250Y242689D01*
Y215311D01*
X947189Y210250D01*
X749294D01*
X749264Y210414D01*
G03X744736I-2264J-414D01*
G01X744706Y210250D01*
X692189D01*
X548689Y66750D01*
X422811D01*
X374750Y114811D01*
Y134717D01*
X374910Y134750D01*
G03X375434Y137474I-304J1471D01*
G37*
G36*
G01X373194Y142009D02*
X373190Y139908D01*
X373179Y139876D01*
G03X373232Y138770I1421J-486D01*
G01X373250Y138730D01*
Y136868D01*
X373233Y136830D01*
G03X373216Y136790I1374J-607D01*
G02X372846I-185J76D01*
G03X370984Y137647I-1390J-569D01*
G01X370953Y137637D01*
X369637Y137647D01*
G02X369360Y138332I4J400D01*
G03X369729Y139880I-1055J1069D01*
G01X369718Y139911D01*
X369724Y141986D01*
X369735Y142018D01*
G03X369366Y143577I-1421J487D01*
G02X369647Y144263I280J286D01*
G01X370973Y144258D01*
X371004Y144247D01*
G03X372565Y144615I489J1420D01*
G02X373250Y144334I285J-281D01*
G01Y143165D01*
X373233Y143127D01*
G03X373184Y142040I1374J-607D01*
G01X373194Y142009D01*
G37*
G36*
G01X470689Y180750D02*
X484250Y167189D01*
Y118311D01*
X482189Y116250D01*
X435811D01*
X422972Y129089D01*
X422957Y129122D01*
G03X422212Y129867I-1367J-622D01*
G01X422179Y129882D01*
X416754Y135307D01*
X416836Y135441D01*
G03X414772Y137505I-1284J780D01*
G01X414638Y137423D01*
X412250Y139811D01*
Y147092D01*
G02X412446Y147292I200J0D01*
G03X413917Y148775I-31J1502D01*
G01X413918Y148857D01*
X415547Y150486D01*
X415624Y150490D01*
G03X417049Y151915I-75J1500D01*
G01X417053Y151992D01*
X424973Y159912D01*
X425052Y159915D01*
G03X426500Y161363I-53J1501D01*
G01X426503Y161442D01*
X428122Y163061D01*
X428201Y163064D01*
G03X429650Y164513I-52J1501D01*
G01X429653Y164592D01*
X437572Y172511D01*
X437651Y172514D01*
G03X439099Y173962I-53J1501D01*
G01X439102Y174041D01*
X443877Y178816D01*
X443954Y178820D01*
G03X445379Y180245I-75J1500D01*
G01X445383Y180322D01*
X445811Y180750D01*
X470689D01*
G37*
G36*
G01X1341750Y347178D02*
X1341576Y347156D01*
G03Y342590I297J-2283D01*
G01X1341750Y342568D01*
Y339811D01*
X1339189Y337250D01*
X1324794D01*
X1324764Y337414D01*
G03X1320927Y338681I-2264J-414D01*
G02X1320371Y338690I-273J292D01*
G01X1320250Y338811D01*
Y368193D01*
G03Y370807I-2250J1307D01*
G01Y373189D01*
X1322311Y375250D01*
X1339689D01*
X1341750Y373189D01*
Y347178D01*
G37*
%LPD*%
G75*
G36*
G01X385266Y138533D02*
G02X382603Y139871I-1247J838D01*
G01X382614Y139902D01*
X382638Y142022D01*
X382628Y142054D01*
G02X385300Y143362I1428J466D01*
G03X385962I331J224D01*
G02X388623Y142022I1244J-842D01*
G01X388612Y141991D01*
X388590Y139875D01*
X388600Y139844D01*
G02X385929Y138534I-1427J-468D01*
G03X385266Y138533I-331J-224D01*
G37*
G36*
G01X401542Y139885D02*
Y142006D01*
X401532Y142037D01*
G02X404197Y143363I1422J483D01*
G03X404860I331J224D01*
G02X407525Y142037I1243J-843D01*
G01X407514Y142005D01*
Y139886D01*
X407525Y139854D01*
G02X404859Y138529I-1422J-483D01*
G03X404197Y138528I-331J-225D01*
G02X401531Y139854I-1244J842D01*
G01X401542Y139885D01*
G37*
G36*
G01X394769Y138520D02*
G02X392087Y139821I-1259J819D01*
G01X392098Y139852D01*
X392094Y142003D01*
X392084Y142035D01*
G02X394749Y143362I1421J485D01*
G03X395411I331J224D01*
G02X398081Y142050I1243J-842D01*
G01X398071Y142018D01*
X398090Y139889D01*
X398101Y139858D01*
G02X395436Y138525I-1418J-496D01*
G03X394769Y138520I-332J-223D01*
G37*
G54D54*
X490944Y79921D03*
G54D55*
X332086Y408858D03*
G54D17*
X50000Y659500D03*
X58804Y699720D03*
X109000Y844220D03*
X111000Y981500D03*
X124500Y515500D03*
X128000Y544050D03*
X121200Y584278D03*
X166200Y506500D03*
X172000Y486400D03*
X182000Y577500D03*
X176938Y680465D03*
X182500Y677500D03*
X242500Y565500D03*
X234000Y562000D03*
X238500Y705000D03*
X253500Y707250D03*
X294500Y98500D03*
X313402Y156000D03*
X305155Y504900D03*
X331040Y152601D03*
X330929Y148600D03*
X317248Y156000D03*
X326000Y292500D03*
X320238Y497183D03*
X316273Y520282D03*
X347000Y120040D03*
X340000D03*
X344055Y529000D03*
X340055Y524000D03*
X342971Y525750D03*
X339000Y878500D03*
X336000Y871500D03*
X339000Y894000D03*
Y885500D03*
X337300Y949500D03*
X353740Y133300D03*
X352040Y143000D03*
X349829Y153400D03*
X355084Y172441D03*
X351929Y162200D03*
X362036Y177155D03*
X358858Y177128D03*
X358848Y174010D03*
X358879Y192929D03*
X351320Y194520D03*
X361987Y189747D03*
X358850Y196050D03*
X355090Y195660D03*
X355139Y190099D03*
X351731Y190274D03*
X362500Y286000D03*
X348000Y292500D03*
X361155Y496203D03*
X356555Y513000D03*
X357055Y507000D03*
X356055Y502000D03*
X374606Y136221D03*
X368296Y136246D03*
X371456Y136221D03*
X368305Y139401D03*
X371482Y133058D03*
X365133Y129133D03*
X374600Y139390D03*
X377750Y139400D03*
X377787Y148812D03*
X368333Y155107D03*
X365140Y155100D03*
X368333Y148827D03*
X368329Y151956D03*
X371493Y145667D03*
X368314Y142505D03*
Y145680D03*
X371457Y155080D03*
X377759Y152000D03*
X365146Y151942D03*
X365182Y142532D03*
X374607Y142520D03*
X377757D03*
X368309Y170830D03*
X368334Y167706D03*
X365158Y164554D03*
X368325Y164585D03*
X368326Y161400D03*
X368271Y158268D03*
X374582Y161404D03*
X374577Y164559D03*
X377750Y170846D03*
X374570Y158267D03*
X365176Y161400D03*
X365187Y186605D03*
X368308Y177202D03*
X374560Y177210D03*
X371485Y177175D03*
X368307Y205511D03*
Y199211D03*
X368336Y192904D03*
X374606Y189763D03*
Y192912D03*
X377756Y211810D03*
X365158D03*
X371457D03*
X367665Y363430D03*
X368055Y380500D03*
X368555Y385000D03*
Y376500D03*
X371781Y387924D03*
X368555Y389000D03*
X368165Y393402D03*
X370500Y518000D03*
X379500Y963500D03*
X390354Y136221D03*
X380906Y136220D03*
X387173Y139376D03*
X392240Y129000D03*
X383680Y129030D03*
X396683Y139362D03*
X393510Y139340D03*
X384019Y139371D03*
X380907Y142520D03*
X387206Y145670D03*
X390355Y142520D03*
X393505Y145670D03*
X387206Y142520D03*
X384056D03*
X390339Y151990D03*
X396639D03*
X380888Y148799D03*
X396655Y142520D03*
X393505D03*
X387205Y167715D03*
X384041Y170888D03*
X380928Y167701D03*
X393528Y167702D03*
X384030Y177120D03*
X393542Y186614D03*
X393490Y174039D03*
X393541Y180315D03*
X384036Y189747D03*
X393519Y192900D03*
X387209Y192930D03*
X384055Y211810D03*
X393504Y218109D03*
X395500Y237000D03*
X389500Y319150D03*
X392589Y317729D03*
X394055Y335000D03*
X391325Y324520D03*
X386755Y326100D03*
X384160Y328812D03*
X391555Y338350D03*
X393061Y346800D03*
X393755Y350500D03*
X390230Y349327D03*
X396055Y338000D03*
X395855Y366890D03*
X392991Y365797D03*
X391628Y358852D03*
X394915Y359725D03*
X387515Y365500D03*
X387265Y384370D03*
X394935Y385150D03*
X382803Y385207D03*
X391215Y384900D03*
X396490Y388597D03*
X388500Y400575D03*
X390543Y391950D03*
X387000Y404275D03*
X388750Y951750D03*
X387061Y986061D03*
X389500Y992000D03*
X402950Y133050D03*
X399835Y139375D03*
X412429Y136210D03*
X402953Y139370D03*
X402800Y129180D03*
X406103Y139371D03*
X412415Y148794D03*
X399779Y142531D03*
X399804Y145670D03*
X412403Y142520D03*
X406125Y148804D03*
X402954Y142520D03*
X406103D03*
X402938Y151950D03*
X399827Y167702D03*
X406140Y167716D03*
X406127Y161404D03*
X412427D03*
X412426Y167703D03*
X399841Y186614D03*
X399840Y180315D03*
X399790Y174039D03*
X406126Y174003D03*
X406139Y180315D03*
X406101Y186613D03*
X412426Y174003D03*
X412439Y186614D03*
X412400Y180314D03*
X406128Y192901D03*
X399791Y192938D03*
X412428Y192901D03*
X399803Y211810D03*
X406102D03*
X406099Y214950D03*
X409249Y214965D03*
X412767Y233162D03*
X400000Y237500D03*
X409500Y271500D03*
X404920Y330117D03*
X412794D03*
X408857Y334054D03*
X400983D03*
X397983Y333998D03*
X408857Y330117D03*
X400523Y325283D03*
X412815Y349860D03*
X408857Y341928D03*
X397555Y345146D03*
X398055Y350296D03*
X398555Y339283D03*
X408857Y345865D03*
X404965Y342120D03*
X412794Y337991D03*
X400055Y343146D03*
X408857Y365550D03*
Y357676D03*
X397117Y364138D03*
X412794Y353739D03*
X404920Y369487D03*
X412794Y361613D03*
X408925Y361680D03*
X400395Y362450D03*
X400885Y354120D03*
X404935Y353840D03*
X412794Y369487D03*
X408857D03*
Y353739D03*
Y385237D03*
Y377363D03*
X412794Y381300D03*
X399923Y372000D03*
X408857Y400985D03*
Y393111D03*
Y389174D03*
X400983Y400985D03*
X404920Y397048D03*
Y400985D03*
Y389174D03*
X412794Y397048D03*
Y389174D03*
X408857Y397048D03*
X400983D03*
X404920Y393111D03*
X408857Y416733D03*
Y408859D03*
X400983Y404922D03*
X412794Y412796D03*
X404920Y404922D03*
X408857D03*
Y412796D03*
X412794Y404922D03*
X404920Y416733D03*
X400983D03*
X408857Y424607D03*
Y420670D03*
X412794D03*
X404555Y430500D03*
X404920Y420670D03*
X406555Y428300D03*
X428375Y119735D03*
X418940Y125000D03*
X415552Y136221D03*
X421590Y128500D03*
X418702Y136221D03*
X413540Y128500D03*
X425000Y136220D03*
X428116Y136218D03*
X421851Y136221D03*
X423686Y126215D03*
X415549Y151990D03*
X418702Y142520D03*
X425001D03*
X418700Y148818D03*
X428149D03*
X415551D03*
X424999D03*
X421850D03*
X428149Y164565D03*
X424999Y161416D03*
X428149D03*
X418726Y167703D03*
Y174003D03*
Y180303D03*
X418701Y186614D03*
X424999Y192912D03*
X418727Y192902D03*
X428150Y211810D03*
X415551D03*
X421850D03*
X428172Y221320D03*
X424979Y218127D03*
X428047Y218049D03*
X415551Y218109D03*
X418729Y218100D03*
X421850Y218109D03*
X418729Y221268D03*
X420500Y234500D03*
X422630Y227232D03*
X426147Y230982D03*
X420714Y225190D03*
X429444Y230192D03*
X419000Y227405D03*
X427965Y318293D03*
X419913Y318051D03*
X417650Y316400D03*
X416482Y319022D03*
X424555Y318000D03*
X420668Y330117D03*
X428542D03*
X424023Y320783D03*
X424605Y334054D03*
Y330117D03*
X416731D03*
X416950Y321783D03*
X416731Y334054D03*
X424605Y345865D03*
X420668Y337991D03*
X428542Y349802D03*
Y341928D03*
X424605Y337991D03*
X428542D03*
X420668Y341928D03*
X424605Y349802D03*
X420668D03*
X416731Y337991D03*
X420668Y345865D03*
X416731Y341928D03*
X424605D03*
Y369487D03*
Y361613D03*
Y353739D03*
X420668Y357676D03*
X428542Y365550D03*
X416731Y369487D03*
X420668Y353739D03*
X416731Y365550D03*
X424605D03*
X420668D03*
X416731Y361613D03*
X420668Y369487D03*
X424605Y357676D03*
X420668Y361613D03*
X416555Y357500D03*
X428542Y357676D03*
X424605Y385237D03*
X428542Y381300D03*
X428500Y377000D03*
X416731Y381300D03*
Y377363D03*
X428445Y373550D03*
X420668Y377363D03*
Y385237D03*
X416731D03*
X424605Y381300D03*
X420668D03*
X424605Y393111D03*
X416731Y389174D03*
X428555Y393000D03*
X420668Y389174D03*
X416731Y393111D03*
Y397048D03*
X420668Y393111D03*
X424605Y397048D03*
X428542Y389174D03*
X420668Y397048D03*
X416731Y400985D03*
X424605Y389174D03*
Y404922D03*
Y408859D03*
X420668Y404922D03*
X428542Y408859D03*
X420668D03*
X428542Y404922D03*
X416731Y416733D03*
Y404922D03*
Y412796D03*
X424605D03*
X416731Y420670D03*
Y424607D03*
X432540Y123000D03*
X435640D03*
X437599Y136221D03*
X434450D03*
X439540Y124500D03*
X431407Y136285D03*
X440931Y129061D03*
X431348Y125911D03*
X442323Y126000D03*
X437945Y127159D03*
X434449Y155118D03*
X431300Y142520D03*
X437599D03*
X440765Y145670D03*
X443928Y148811D03*
X443891Y151999D03*
X443890Y142565D03*
X443909Y145650D03*
X443936Y155118D03*
X431299Y164565D03*
X434449Y167716D03*
Y161417D03*
X431299Y161416D03*
X443899Y161430D03*
X443882Y167737D03*
X443899Y164530D03*
X443871Y158278D03*
X437598Y174015D03*
Y180314D03*
Y186614D03*
X443910Y174041D03*
X443879Y180320D03*
X443887Y177138D03*
X440769Y183480D03*
X443919D03*
X437598Y205511D03*
Y199212D03*
Y192913D03*
X443897Y205512D03*
Y192914D03*
X443898Y199212D03*
X443897Y202363D03*
Y196063D03*
X437598Y211810D03*
X443897Y211811D03*
Y208662D03*
X431336Y218111D03*
X434448Y218109D03*
X437598D03*
X436529Y229500D03*
X434334Y226789D03*
X443113Y226339D03*
X439980Y232126D03*
X441379Y229700D03*
X432307Y224857D03*
X437112Y232239D03*
X445892Y225995D03*
X438500Y250000D03*
X431023Y317283D03*
X430513Y320841D03*
X436416Y330117D03*
X444290D03*
X440353Y334054D03*
X432523Y330283D03*
X444555Y334000D03*
X441335Y321000D03*
X436416Y334054D03*
X440353Y349802D03*
X444290D03*
X440353Y341928D03*
X436416Y345865D03*
X432365Y341880D03*
X444290Y337991D03*
X432605Y337880D03*
X444290Y345865D03*
X440353D03*
X440555Y338000D03*
X440353Y353739D03*
X432479Y369487D03*
Y361613D03*
X444290Y369487D03*
X436416D03*
X440353Y357676D03*
X444290Y353739D03*
X440353Y365550D03*
X436416Y353739D03*
Y361613D03*
X432479Y385237D03*
Y377363D03*
X444290Y381300D03*
X440353Y377363D03*
X436416Y381300D03*
X444290Y397048D03*
X440353D03*
X436416D03*
X444290Y400985D03*
X436416D03*
X444290Y389174D03*
X436416D03*
X432479Y408859D03*
Y404922D03*
X436416D03*
Y408859D03*
X444290Y404922D03*
Y408859D03*
X440353D03*
Y404922D03*
Y412796D03*
X432479D03*
X448669Y126510D03*
X450209Y129230D03*
X447389Y129580D03*
X454676Y137495D03*
X456429Y135000D03*
X457929Y132500D03*
X451679Y148250D03*
X461685Y150386D03*
X455731Y154302D03*
X460300Y141100D03*
X454929Y146500D03*
X453929Y140334D03*
X459069Y151980D03*
X451329Y165570D03*
X453599Y156693D03*
X450196Y189764D03*
X454329Y199800D03*
X452929Y203900D03*
X452329Y194300D03*
X447063Y199234D03*
X447047Y189764D03*
X451292Y197637D03*
X456479Y202400D03*
X455929Y192800D03*
X456229Y196700D03*
X453829Y215600D03*
X453729Y219300D03*
X452393Y210236D03*
X458029Y213469D03*
X457798Y217769D03*
X457729Y206800D03*
X448840Y225775D03*
X455429Y227500D03*
X451929Y229800D03*
X456929Y224507D03*
X456103Y330117D03*
X452223Y333983D03*
X448227Y334054D03*
X460040D03*
X456103D03*
X460040Y349802D03*
Y341928D03*
X448227Y349802D03*
Y341928D03*
X460040Y337991D03*
X455825Y349840D03*
X448000Y346000D03*
X456055Y338000D03*
X452055D03*
X452165Y349470D03*
X456103Y369487D03*
Y353739D03*
Y361613D03*
X460040Y357676D03*
Y365550D03*
X448227D03*
Y357676D03*
X460040Y385237D03*
X456103Y381300D03*
X460040Y377363D03*
X448227Y385237D03*
Y377363D03*
X456103Y397048D03*
X448227D03*
X456103Y389174D03*
X456223Y404883D03*
Y408783D03*
X452123Y416783D03*
X460040Y412796D03*
X448227D03*
X452223Y404883D03*
X448227Y408859D03*
X452223Y408783D03*
X448227Y404922D03*
X471480Y105660D03*
X466464Y151000D03*
X466500Y144500D03*
X463969Y147610D03*
X464570Y215750D03*
X467300Y320100D03*
X471851Y322243D03*
Y326180D03*
X463977Y330117D03*
Y334054D03*
X467914D03*
X475788Y330117D03*
X471851Y337991D03*
X467914D03*
X463977D03*
X471851Y349802D03*
X467914Y345865D03*
X471851Y361613D03*
Y369487D03*
Y353739D03*
Y357676D03*
X463977Y369487D03*
Y361613D03*
X471851Y377363D03*
Y381300D03*
X463977D03*
Y400985D03*
X471851D03*
Y389174D03*
X463977D03*
Y408859D03*
Y404922D03*
X467914Y408859D03*
Y404922D03*
X475788Y412796D03*
X471851Y416733D03*
X467914Y412796D03*
X480500Y181800D03*
X483955Y318600D03*
X487500Y333833D03*
X483662Y334054D03*
X487599Y330117D03*
X483662Y326180D03*
X484000Y322000D03*
X487599Y326180D03*
X487155Y321900D03*
X483662Y330117D03*
X487599Y337991D03*
X483662D03*
Y341928D03*
X487599D03*
X483662Y345865D03*
X487599Y349802D03*
X483662D03*
X487599Y345865D03*
X479725Y341928D03*
Y349802D03*
X487603Y369483D03*
X483662Y357676D03*
X487599D03*
X483663Y365463D03*
X483662Y361613D03*
Y353739D03*
X487599D03*
X483683Y369403D03*
X491536Y369487D03*
Y361613D03*
X479725Y365550D03*
Y357676D03*
X491536Y381300D03*
X479725Y385237D03*
Y377363D03*
X491536Y397048D03*
Y389174D03*
X479725Y400985D03*
Y393111D03*
X491536Y412796D03*
Y404922D03*
X483662Y412796D03*
Y404922D03*
X479725Y416733D03*
X487599Y420670D03*
X495473Y334054D03*
Y341928D03*
Y385237D03*
Y377363D03*
Y400985D03*
Y393111D03*
X521700Y114000D03*
X533441Y211775D03*
X559750Y264500D03*
X568500Y147500D03*
X605000Y209500D03*
X604500Y227500D03*
Y223000D03*
X599000Y804000D03*
X622500Y696500D03*
X625000Y706000D03*
X632500Y530000D03*
X691400Y231100D03*
X710100Y182700D03*
X780000Y250000D03*
X862500Y65000D03*
X865000Y488500D03*
X874000Y56000D03*
X873500Y61500D03*
X884500Y323500D03*
X881000Y736500D03*
X945000Y141500D03*
X947500Y153000D03*
X959900Y180700D03*
X974500Y188500D03*
X975007Y194300D03*
X1002500Y653000D03*
X1001100Y776500D03*
X1015000Y477500D03*
X1011500Y667500D03*
X1022000Y492500D03*
X1022500Y637500D03*
X1027504Y853366D03*
X1045000Y266600D03*
X1041410Y695394D03*
Y690694D03*
Y699834D03*
X1055000Y214500D03*
X1055500Y360000D03*
X1062940Y629945D03*
X1065978Y664568D03*
X1063056Y681554D03*
X1062700Y672600D03*
X1054080Y680630D03*
X1084500Y223500D03*
X1074000Y660500D03*
X1074500Y665500D03*
X1088000Y461000D03*
X1103300Y492000D03*
X1114500Y645000D03*
X1118630Y714820D03*
X1116550Y783600D03*
X1119060Y791083D03*
X1132500Y333000D03*
X1126500Y614500D03*
X1132423Y663902D03*
X1135553Y663957D03*
X1132440Y676555D03*
X1129272Y673350D03*
X1129271Y670275D03*
X1126102Y676518D03*
X1132402Y673405D03*
X1132398Y667102D03*
X1129290Y676555D03*
X1126121Y679722D03*
X1132421Y679648D03*
X1132395Y670225D03*
X1126117Y685952D03*
X1129273Y689170D03*
X1126122Y689171D03*
X1129290Y692303D03*
X1126116Y692279D03*
X1132423Y695469D03*
X1132440Y692265D03*
Y686004D03*
X1132434Y682860D03*
X1129278Y682804D03*
X1129289Y686005D03*
X1126157Y695435D03*
X1129238Y704878D03*
X1132440Y701714D03*
X1129270D03*
X1126121Y711218D03*
X1129285Y708056D03*
X1126114Y701703D03*
X1126093Y704874D03*
X1132406Y704904D03*
X1132440Y698564D03*
X1129290D03*
X1126155Y708029D03*
X1132445Y714345D03*
X1129260Y714350D03*
X1126121Y714368D03*
X1132417Y711189D03*
X1129277Y711210D03*
X1128959Y729952D03*
X1126969Y727981D03*
X1132459Y717481D03*
X1127183Y740805D03*
X1126671Y744629D03*
X1126885Y736721D03*
X1123393Y743726D03*
X1124497Y734140D03*
X1124326Y738960D03*
X1126955Y731909D03*
X1124978Y747578D03*
X1130900Y766700D03*
X1124460Y768140D03*
X1125900Y764200D03*
X1129501Y776929D03*
X1120400Y781600D03*
X1126360Y792640D03*
X1127160Y788837D03*
X1129497Y792673D03*
X1130610Y788820D03*
X1134145Y788450D03*
X1132684Y792636D03*
X1124360Y788390D03*
X1132600Y784822D03*
X1120529Y786350D03*
X1123254Y792663D03*
X1131095Y799965D03*
X1124796Y800150D03*
X1144425Y325500D03*
X1143000Y629000D03*
X1138757Y663937D03*
X1151354Y663936D03*
X1148150Y663956D03*
X1141900Y663944D03*
X1148188Y667106D03*
Y670256D03*
X1151282Y667088D03*
X1141600Y673590D03*
X1141954Y676581D03*
X1135589Y673368D03*
X1144983Y667085D03*
X1145020Y670200D03*
X1136150Y676500D03*
X1135685Y679613D03*
X1135598Y667080D03*
X1135595Y670225D03*
X1141868Y670273D03*
X1138708Y667113D03*
X1139245Y675106D03*
X1135589Y682854D03*
Y695415D03*
X1139858Y692074D03*
X1139000Y685667D03*
X1144880Y707720D03*
X1145000Y711200D03*
X1138729Y714360D03*
X1151307Y714306D03*
X1141765Y711030D03*
X1145053Y714327D03*
X1148169Y711219D03*
X1141840Y714339D03*
X1138320Y710066D03*
X1135589Y701714D03*
X1151352Y711178D03*
X1140710Y707750D03*
X1138400Y705300D03*
X1136304Y707482D03*
X1151318Y717518D03*
X1148135Y720634D03*
X1138685Y720633D03*
X1141870Y717518D03*
X1148167Y717517D03*
X1138730Y717480D03*
X1141904Y720633D03*
X1150734Y736950D03*
X1149470Y734451D03*
X1137030Y745300D03*
X1146370Y769310D03*
X1142095Y773774D03*
X1151564Y776924D03*
X1146200Y766300D03*
X1142323Y780250D03*
X1138961Y776940D03*
X1150310Y783840D03*
X1142120Y795830D03*
X1145270D03*
X1138970D03*
X1145270Y792670D03*
X1141700Y785113D03*
X1138545Y787952D03*
X1145740Y789140D03*
X1138931Y792658D03*
X1142086Y789513D03*
X1136236Y782142D03*
X1151590Y792660D03*
X1143470Y782805D03*
X1141100Y831600D03*
X1157599Y663956D03*
X1167098Y663932D03*
X1160748Y660807D03*
Y657657D03*
X1160741Y663949D03*
X1163946Y663946D03*
X1157613Y673418D03*
X1167692Y674996D03*
X1160768Y676535D03*
X1154470Y673363D03*
X1152090Y677010D03*
X1163917Y670275D03*
X1160741Y667099D03*
X1163914Y673352D03*
X1167034Y667092D03*
X1157655Y667087D03*
X1160770Y673421D03*
X1163944Y667076D03*
X1154487Y670256D03*
X1157670Y707960D03*
X1167048Y714312D03*
X1163968Y708000D03*
X1154434Y714335D03*
X1157581Y714331D03*
X1163905Y711206D03*
X1157636Y711200D03*
X1167103Y711107D03*
X1167000Y727500D03*
X1157637Y717463D03*
X1157643Y720642D03*
X1152248Y730404D03*
X1154430Y717481D03*
X1152400Y727600D03*
X1167049Y717501D03*
X1167048Y720612D03*
X1163898Y717462D03*
Y720612D03*
X1157112Y731702D03*
X1164200Y744500D03*
X1157000Y734500D03*
X1163830Y747899D03*
X1158100Y769700D03*
X1162450Y769190D03*
X1167002Y767508D03*
X1167326Y776936D03*
X1161051Y792660D03*
X1164196Y795814D03*
X1153219Y781303D03*
X1161545Y788844D03*
X1162693Y780865D03*
X1158092Y787715D03*
X1154712Y792690D03*
X1165492Y780957D03*
X1154200Y788900D03*
X1154700Y795790D03*
X1161022Y785693D03*
X1165063Y787500D03*
X1167410Y785530D03*
X1154800Y799000D03*
X1173332Y663938D03*
X1176506Y663916D03*
X1176525Y679676D03*
X1170181Y670240D03*
X1176503Y670218D03*
X1182803Y670234D03*
X1176534Y673368D03*
X1179653Y670234D03*
X1173309Y673406D03*
X1179662Y673421D03*
X1176534Y676555D03*
X1179667Y679655D03*
X1182831Y679666D03*
X1182815Y676573D03*
X1170192Y667100D03*
X1176526Y667092D03*
X1173403Y670237D03*
X1173349Y667099D03*
X1182785Y685977D03*
X1176520Y685970D03*
X1179663Y685959D03*
X1173365Y695397D03*
X1169800Y682200D03*
X1173392Y685974D03*
X1173389Y689121D03*
X1176482Y682840D03*
X1176529Y692276D03*
X1179685Y692292D03*
X1176496Y695415D03*
X1179664Y695466D03*
X1182796Y695415D03*
X1179678Y689111D03*
X1182817Y689155D03*
X1173384Y692265D03*
X1182815Y701696D03*
X1182796Y708013D03*
X1182813Y698619D03*
X1170248Y714330D03*
X1173350Y698590D03*
X1179703Y714331D03*
X1173347Y714350D03*
X1176503Y714342D03*
X1176515Y704845D03*
X1179676Y711207D03*
X1179660Y704850D03*
X1171200Y706170D03*
X1179660Y708050D03*
X1176515Y708045D03*
X1173015Y708329D03*
X1176515Y711144D03*
X1173262Y711119D03*
X1182802Y714356D03*
X1169282Y729708D03*
X1173400Y717480D03*
X1176499Y720609D03*
X1170199Y717501D03*
X1173348Y720613D03*
X1176489Y717469D03*
X1171500Y733725D03*
X1175000Y734870D03*
X1171108Y777368D03*
X1170950Y795960D03*
X1170911Y784912D03*
X1170718Y782118D03*
X1185965Y676573D03*
X1190500Y674207D03*
X1190000Y699500D03*
Y705500D03*
X1199500Y743500D03*
X1201250Y627000D03*
X1218040Y719850D03*
X1249773Y551500D03*
X1279600Y694800D03*
X1287962Y710490D03*
X1289500Y716500D03*
X1292500Y730478D03*
X1305000Y596500D03*
X1306423Y608164D03*
X1306443Y618985D03*
X1307150Y691500D03*
X1307000Y729100D03*
X1310500Y737500D03*
X1307000Y732500D03*
X1300491Y732991D03*
X1322900Y524600D03*
X1322400Y533100D03*
X1318000Y696500D03*
X1319000Y708000D03*
X1351900Y524600D03*
X1352400Y533600D03*
X1381415Y581195D03*
X1380925Y598315D03*
X1377996Y610847D03*
X1380925Y602035D03*
X1377996Y607382D03*
X1385135Y581195D03*
G54D13*
X8200Y857700D03*
X8000Y853500D03*
X35304Y832220D03*
X34304Y897720D03*
X47483Y387776D03*
X43883Y387769D03*
X52000Y655500D03*
X44804Y837220D03*
X44500Y851500D03*
X49000Y861500D03*
X52000Y872720D03*
X37232Y877242D03*
X51896Y878668D03*
X42554Y891720D03*
X37211Y881115D03*
X37758Y884674D03*
X40304Y887220D03*
X51304Y882220D03*
X47804Y906720D03*
X43804Y907720D03*
X41304Y927220D03*
X50270Y929186D03*
X62783Y387776D03*
X66483Y387876D03*
X56883D03*
X53183Y387676D03*
X55304Y669720D03*
X58804Y710220D03*
X68147Y722511D03*
X62704Y739620D03*
X55304Y746220D03*
X65272Y758504D03*
X64683Y762056D03*
X59272Y790504D03*
X57772Y801504D03*
X61492Y803004D03*
X55022Y826720D03*
X66022Y827254D03*
X57304Y815720D03*
X61304Y815220D03*
X65804Y835720D03*
X57804Y834720D03*
X61804D03*
X52304Y868220D03*
X60804Y907720D03*
X56804Y907220D03*
X52304Y906720D03*
X64804Y907720D03*
X52804Y943220D03*
X57770Y932686D03*
X55270Y929186D03*
X52770Y932686D03*
X62770D03*
X60270Y929186D03*
X52804Y938795D03*
X71883Y387976D03*
X76083D03*
X76804Y710220D03*
X71846Y722426D03*
X77272Y724004D03*
X75432Y735059D03*
X83849Y735513D03*
X80272Y735103D03*
X68910Y760642D03*
X83112Y760720D03*
X75432Y758844D03*
X80624Y764241D03*
X68762Y764239D03*
X82804Y794920D03*
X84804Y808720D03*
X79000Y836500D03*
X84221Y836078D03*
X77500Y832000D03*
X70909Y847325D03*
X72304Y869720D03*
X76304D03*
X81304Y884470D03*
X89804Y669720D03*
X95304Y686220D03*
X94804Y708220D03*
X99804Y709220D03*
X87772Y735059D03*
X92365Y735040D03*
X85672Y763504D03*
X86404Y774720D03*
X85304Y768720D03*
X93347Y765754D03*
X85204Y798220D03*
X92304Y835720D03*
X87928Y848107D03*
X95700Y926300D03*
X105000Y834500D03*
X113222Y831222D03*
X112500Y835000D03*
X110500Y848500D03*
X115500D03*
X109054Y892720D03*
X102304Y895220D03*
X114054Y892720D03*
X106554Y895720D03*
X116554D03*
X111554Y896220D03*
X105804Y943220D03*
X109054Y932720D03*
X116600Y929924D03*
X114054Y932470D03*
X111554Y929720D03*
X108804Y938795D03*
X115500Y983500D03*
X127654Y293453D03*
X132123Y318877D03*
X123654Y320953D03*
X131500Y324000D03*
X122906Y331953D03*
X127301Y354709D03*
X131147D03*
X132500Y547000D03*
Y559600D03*
Y556000D03*
Y551500D03*
X133500Y582500D03*
X125050Y583000D03*
X126500Y587500D03*
X121685Y587919D03*
X134000Y587000D03*
X130000Y666500D03*
X129304Y798720D03*
X122500Y845500D03*
X128000Y870500D03*
X129100Y892924D03*
X124054Y892220D03*
X121600Y895266D03*
X119054Y892720D03*
X126554Y895470D03*
X121598Y929924D03*
X131554Y929470D03*
X129054Y932720D03*
X126554Y929882D03*
X124098Y932515D03*
X119099Y932516D03*
X118000Y991500D03*
X145500Y283500D03*
X143147Y354709D03*
X139301D03*
X135500Y511000D03*
X136000Y566000D03*
X136500Y576900D03*
Y573300D03*
Y580500D03*
Y569700D03*
X140500Y568000D03*
X144000Y572500D03*
X143500Y710500D03*
X141054Y795820D03*
X150225Y790412D03*
X146304Y804220D03*
X146500Y808220D03*
X165793Y294309D03*
X155874Y313961D03*
Y317807D03*
X164147Y328699D03*
X155874Y326957D03*
Y323111D03*
X155147Y354709D03*
X162801D03*
X166647D03*
X151301D03*
X160000Y465500D03*
X158500Y461500D03*
X153050Y486500D03*
X163225Y522080D03*
X154625Y550290D03*
X154755Y539310D03*
X163305Y554750D03*
X160500Y586500D03*
X156900D03*
X152948Y587000D03*
X166000Y662500D03*
X157750Y662250D03*
X166500Y650500D03*
X162500Y670000D03*
X163000Y710500D03*
X150900Y812500D03*
X154500D03*
X152500Y840000D03*
X157500Y867500D03*
X169639Y294309D03*
X179088Y294909D03*
X175242D03*
X167993Y328699D03*
X179622Y328749D03*
X175776D03*
X182800Y465800D03*
X171500Y478699D03*
X177493Y533493D03*
X170339Y537396D03*
X180555Y560500D03*
X175993Y559938D03*
X175055Y569500D03*
X167469Y588969D03*
X174000Y830500D03*
X170500Y835500D03*
X179500Y847000D03*
X172000Y868000D03*
X168400D03*
X183000Y865750D03*
X188295Y297209D03*
X193841Y297755D03*
X185039Y295209D03*
X191295D03*
X186614Y319028D03*
X190295Y318709D03*
X198864Y323297D03*
X192874Y334307D03*
Y330461D03*
X184295Y322209D03*
X192795Y321709D03*
X192874Y341611D03*
Y345457D03*
X192500Y431500D03*
X187300Y457300D03*
X191800D03*
X190800Y462800D03*
X189355Y526470D03*
X195725Y540750D03*
X198500Y563000D03*
X194500Y724000D03*
X186000Y841500D03*
X185000Y856000D03*
X185500Y848260D03*
X187000Y878000D03*
X199000Y891500D03*
X190500Y894000D03*
X195000Y891500D03*
X204285Y294909D03*
X213733D03*
X200439D03*
X209887D03*
X208338Y323297D03*
X202710D03*
X212134D03*
X212500Y435000D03*
X204500Y470000D03*
X208305Y562640D03*
X203000Y564500D03*
X212500Y716500D03*
X204500Y721000D03*
X215250Y833750D03*
X205500Y830000D03*
X204000Y862000D03*
X212000Y891500D03*
X203500Y894000D03*
X208000Y892000D03*
X232500Y419000D03*
Y431000D03*
X229055Y497000D03*
X216500Y516000D03*
X228319Y524798D03*
X230000Y680500D03*
X221000Y723000D03*
X218000Y801500D03*
X223500Y825500D03*
X228000Y825000D03*
X232000D03*
X227000Y858000D03*
X217000Y858500D03*
X222000Y853500D03*
Y858500D03*
Y863500D03*
Y893600D03*
X243755Y490890D03*
X242003Y506327D03*
X234755Y509700D03*
X245205Y504679D03*
X246613Y501365D03*
X237055Y513500D03*
X234185Y527138D03*
X248855Y532300D03*
X239555Y519500D03*
X247500Y829500D03*
X237953Y861453D03*
X259055Y500500D03*
X260288Y514589D03*
X264655Y511100D03*
X250055Y510800D03*
X256055Y531016D03*
X260555Y525500D03*
X253679Y523137D03*
X260605Y519245D03*
X263555Y534500D03*
X261255Y549000D03*
X265455Y544853D03*
X252055Y548760D03*
X257555Y549000D03*
X251000Y835500D03*
X251500Y855500D03*
X252000Y846500D03*
X252500Y851500D03*
X250362Y865000D03*
X253610Y863447D03*
X279997Y514179D03*
X275555Y531500D03*
X275055Y521825D03*
X266055Y531725D03*
X272571Y541150D03*
X278367Y535140D03*
X269555Y536000D03*
X271451Y544616D03*
X278676Y539500D03*
X270000Y870000D03*
Y865500D03*
X276500Y888500D03*
X280500Y955000D03*
X278050Y958500D03*
X296200Y94400D03*
X297929Y332000D03*
Y336000D03*
X293929Y342000D03*
X292525Y498780D03*
X292045Y504897D03*
X293273Y509500D03*
X282626Y516639D03*
X291530Y525407D03*
X283103Y520208D03*
X286588Y519305D03*
X292555Y533043D03*
X291755Y529000D03*
X286555Y524524D03*
X282555Y540700D03*
X283038Y536850D03*
X309500Y78500D03*
X313250Y85250D03*
X311500Y81500D03*
X314000Y102500D03*
X302000Y94300D03*
X299831Y144328D03*
X303677D03*
X305852Y163800D03*
X309698D03*
X299395Y449160D03*
X303545Y445840D03*
X312925Y462560D03*
X300112Y483783D03*
X305055Y472500D03*
X302555Y476000D03*
X312773Y529878D03*
X305255Y542600D03*
X313000Y582000D03*
X327000Y89500D03*
X323000D03*
X319309Y89503D03*
X317500Y101000D03*
X324200Y101900D03*
X330000Y118500D03*
X325929D03*
X321500D03*
X327100Y136294D03*
Y139857D03*
X326422Y152507D03*
Y148944D03*
X319800Y146898D03*
Y143052D03*
X322229Y218800D03*
X316129Y213000D03*
X328000Y285000D03*
X327000Y308000D03*
X331000Y308018D03*
X330555Y467500D03*
X325873Y477006D03*
X325854Y480606D03*
X330491Y525490D03*
X315725Y549790D03*
X321555Y534500D03*
X329695Y534650D03*
X315135Y554980D03*
X317758Y581297D03*
X329055Y569500D03*
X321780Y575000D03*
X314930Y585500D03*
X321500Y688000D03*
X333000Y90500D03*
X343000Y89000D03*
X339500Y75500D03*
X337500Y84250D03*
X342000Y102000D03*
X346000D03*
X334500Y118500D03*
X334600Y129468D03*
Y133031D03*
X344429Y312000D03*
X341500Y309500D03*
X343929Y320700D03*
X345929Y336500D03*
X341351Y336434D03*
X344929Y325500D03*
X342500Y340000D03*
X343095Y446200D03*
X338985Y467405D03*
X338595Y482590D03*
X339140Y512500D03*
X336445Y509330D03*
X343555Y517000D03*
X334055Y526000D03*
X347213Y546700D03*
X334555Y548500D03*
X341055Y534500D03*
X344655D03*
X345500Y556500D03*
X339888Y586388D03*
X346402Y653004D03*
X342500Y653000D03*
X335500Y868000D03*
X332129Y889371D03*
X331829Y885500D03*
X338000Y942000D03*
X339500Y960000D03*
X352000Y66000D03*
X357500Y79500D03*
Y75500D03*
X351929Y332500D03*
X357055Y385000D03*
Y380500D03*
Y376500D03*
X355055Y394000D03*
Y389500D03*
X349575Y479503D03*
X349815Y475550D03*
X358797Y532258D03*
X354055Y534000D03*
X352095Y524040D03*
X362555Y534500D03*
X348255D03*
X360500Y588500D03*
X350000Y652878D03*
X362210Y876200D03*
X363480Y907783D03*
X362000Y904500D03*
X363000Y931500D03*
X359000D03*
X354000Y960000D03*
X363614Y971524D03*
X361000Y974000D03*
X360024Y979100D03*
X366600Y285800D03*
X377855Y300110D03*
X374000Y293500D03*
X372055Y319500D03*
X369555Y322500D03*
X371555Y347500D03*
X375805Y380250D03*
X370275Y413540D03*
X371710Y406535D03*
X369555Y417500D03*
X370575Y409952D03*
X367022Y482783D03*
X373555Y482500D03*
X379000Y531000D03*
X371000Y866500D03*
X376041Y866041D03*
X375500Y906000D03*
Y901500D03*
X365500Y916000D03*
X369341Y916117D03*
X371100Y926000D03*
X377000Y927500D03*
X372300Y918749D03*
X369500Y936500D03*
X368000Y932000D03*
X371000Y930000D03*
X376000Y960000D03*
X364396Y980109D03*
X366878Y977500D03*
X369200Y980252D03*
X372500Y977918D03*
X377464Y987493D03*
X377250Y982250D03*
X390000Y13500D03*
X385000D03*
X388000Y233500D03*
X388149Y229780D03*
X393429Y229500D03*
X395450Y265400D03*
X390100Y263600D03*
X387500Y261000D03*
X381500Y297000D03*
X395104Y291056D03*
X382455Y331870D03*
X386755Y447300D03*
X393055Y451000D03*
Y447400D03*
X385463Y450948D03*
X396055Y456500D03*
X386055Y454500D03*
X381500Y534000D03*
X384046Y536546D03*
X396000Y714500D03*
X392500Y718500D03*
X391000Y866500D03*
X396500Y888500D03*
X396600Y895855D03*
X396330Y899705D03*
X396500Y904000D03*
X384000Y926500D03*
X389838Y942300D03*
X388500Y955250D03*
X390000Y946500D03*
X397900Y231800D03*
X399500Y240500D03*
X412513Y294800D03*
X398385Y292540D03*
X401855Y293500D03*
X408656Y291500D03*
X405555Y293500D03*
X401555Y318000D03*
X406555Y320500D03*
X403255Y425950D03*
X404500Y877300D03*
X397600Y892000D03*
X399500Y901500D03*
X403250Y949000D03*
X408250Y949500D03*
X410500Y954500D03*
X405704Y952046D03*
X398250Y955000D03*
X400750Y952000D03*
X410000Y983500D03*
X410500Y987500D03*
X414000Y8000D03*
X418192Y114237D03*
X421000Y231500D03*
X424929Y264700D03*
X428100Y266500D03*
X419600Y282900D03*
X419455Y293000D03*
X416187Y294711D03*
X429500Y311000D03*
X425278Y802000D03*
X416046Y959546D03*
X414500Y948500D03*
X414215Y952089D03*
X422098Y948630D03*
X418500Y948500D03*
X413500Y957000D03*
X416000Y964000D03*
X420000D03*
X413600Y983500D03*
X438500Y9000D03*
X433929Y100000D03*
X430540Y108750D03*
X433929Y264300D03*
X439800Y284100D03*
X430900Y294550D03*
X439200D03*
X432500Y301000D03*
X435000Y294000D03*
X436416Y357676D03*
X444778Y802100D03*
X438278D03*
X431778Y802000D03*
X431278Y883000D03*
X444278D03*
X437778D03*
X432000Y933500D03*
X430500Y962000D03*
X459429Y106000D03*
X448929Y99500D03*
X457500Y121000D03*
X457429Y171500D03*
X462500Y169000D03*
X458429Y175590D03*
X456000Y243500D03*
X460000D03*
X461100Y260050D03*
X459055Y263500D03*
X456278Y802100D03*
X450778Y883000D03*
X460778D03*
X469000Y113000D03*
X472990Y113350D03*
X462700Y120800D03*
X471429Y133500D03*
X471000Y141000D03*
X467600Y158400D03*
X465600Y162000D03*
X475216Y182917D03*
X470000Y188500D03*
X462679Y176900D03*
X466700Y259400D03*
X464055Y256500D03*
X463371Y290371D03*
X463945Y349700D03*
X475778Y802100D03*
X462778D03*
X469278D03*
X473778Y883000D03*
X467278D03*
X488500Y114200D03*
X481929Y126500D03*
X481429Y150000D03*
X491257Y315952D03*
X495103D03*
X487612Y318606D03*
X480278Y883000D03*
X488000Y904500D03*
X483500Y907500D03*
X499390Y153500D03*
X503500D03*
X503929Y146500D03*
X506429Y149500D03*
X495929Y164500D03*
X508500Y320000D03*
X504453Y314200D03*
X500607D03*
X496155Y321700D03*
X505922Y415371D03*
X506163Y419973D03*
X508100Y605500D03*
X506000Y610000D03*
X513200Y121450D03*
X513000Y156500D03*
X512000Y320000D03*
X519706Y314000D03*
X515860D03*
X527002Y319359D03*
X523348D03*
X526500Y346532D03*
Y342969D03*
Y352969D03*
X520500Y351500D03*
Y347937D03*
Y358937D03*
X526500Y356532D03*
X520500Y362500D03*
X533000Y153800D03*
X528500Y172000D03*
X539714Y179150D03*
X542500Y188500D03*
X537479Y197875D03*
X539073Y237300D03*
X531590Y297620D03*
X534500Y295500D03*
X528500Y310000D03*
X534629Y311171D03*
X534960Y321000D03*
X538614D03*
X529848Y325500D03*
X533502D03*
X550500Y188000D03*
X560500Y186000D03*
X555500Y194000D03*
X559500D03*
X545000Y195000D03*
X549926Y204000D03*
X557275Y214918D03*
X553675Y215913D03*
X550075D03*
X559961Y209419D03*
X546916Y217641D03*
X548000Y231000D03*
X547746Y225303D03*
X559971Y237753D03*
X553555Y321000D03*
X560253Y329500D03*
X557061Y334194D03*
X553155Y334300D03*
X548000Y369500D03*
X555935Y363000D03*
X559500Y604500D03*
X572000Y189000D03*
X571398Y183602D03*
X561429Y174441D03*
X575500Y198400D03*
X576650Y204500D03*
X563100Y194000D03*
X568158Y206455D03*
X571461Y207887D03*
X569000Y217000D03*
X569127Y213100D03*
X564583Y206028D03*
X577119Y233139D03*
X564631Y234356D03*
X569322Y234220D03*
X573179Y233535D03*
X575425Y228505D03*
X563704Y272000D03*
X563555Y333000D03*
X564215Y369339D03*
X566430Y366500D03*
X569555Y364000D03*
X562555Y364500D03*
X587175Y202525D03*
X591413Y199087D03*
X583500Y204500D03*
X585325Y198000D03*
X583325Y208500D03*
X583204Y236805D03*
X580709Y232091D03*
X619876Y195000D03*
X617828Y303250D03*
X613962D03*
X623500Y576500D03*
X622500Y608500D03*
X633578Y303250D03*
X629712D03*
X642800Y433587D03*
X641500Y449500D03*
X636500Y444800D03*
X640500Y444500D03*
X635325Y457500D03*
X628524Y591976D03*
X649323Y303250D03*
X645457D03*
X652714Y428214D03*
X647500Y425500D03*
X645500Y459500D03*
X654300Y490300D03*
X674469Y99380D03*
X674358Y103170D03*
X665073Y303250D03*
X661207D03*
X669025Y441725D03*
X660500Y436538D03*
X669462Y472500D03*
X667056Y475500D03*
X673010Y474436D03*
X673300Y579000D03*
X669000D03*
X663500Y610500D03*
X674688Y696751D03*
X670474Y808700D03*
X671500Y861000D03*
X673500Y864000D03*
X672000Y967750D03*
X667000Y969700D03*
X666750Y961550D03*
X685519Y55019D03*
X676748Y52000D03*
X684861Y58584D03*
X686000Y62000D03*
X684197Y74703D03*
X687500Y440500D03*
X677500Y472500D03*
X688500Y606000D03*
X683000Y603950D03*
X677500Y612000D03*
X680000Y640000D03*
X691000Y704500D03*
X677500Y699000D03*
X682968Y758284D03*
X677500Y773500D03*
X678468Y805284D03*
X691300Y807300D03*
X679000Y865050D03*
X676500Y967750D03*
X706716Y82448D03*
X705500Y575600D03*
X702918Y782734D03*
X704000Y892500D03*
X716034Y53966D03*
X716466Y65466D03*
X711216Y82402D03*
X720216Y82138D03*
X711500Y179400D03*
X725000Y452300D03*
X720700Y564200D03*
X717036Y563783D03*
X709750Y585200D03*
X719918Y754734D03*
X715118Y776134D03*
X717468Y810784D03*
X722000Y808500D03*
X720500Y860000D03*
X710750Y863250D03*
X714000Y867500D03*
X714500Y891000D03*
X740500Y75000D03*
X728100Y213800D03*
X732500Y455500D03*
X736000Y464500D03*
X728500Y482500D03*
X730000Y536500D03*
X733500Y568500D03*
X729900D03*
X741500Y582450D03*
X737000Y583640D03*
X740768Y763984D03*
X735500Y771984D03*
X736000Y810500D03*
X733768Y800734D03*
X741050Y869500D03*
X740000Y886000D03*
X737290Y903000D03*
X733000Y969700D03*
X754500Y67500D03*
X747000Y210000D03*
X755697Y303250D03*
X751484Y540600D03*
X755000Y727500D03*
X757500Y743500D03*
X757000Y896400D03*
X749500Y974300D03*
X759563Y303250D03*
X771447D03*
X773500Y326000D03*
X758500Y457000D03*
X772024Y478976D03*
X774500Y489500D03*
X760500D03*
X766000Y635000D03*
X763000Y648000D03*
X767000Y648500D03*
X771000Y689500D03*
X760500Y707950D03*
X768000Y728000D03*
X763500Y839500D03*
X768000Y833000D03*
X766750Y849250D03*
X774500Y890500D03*
X775748Y188500D03*
X789500Y235837D03*
X787192Y303250D03*
X775313D03*
X779000Y458000D03*
X776000Y478828D03*
X788774Y482774D03*
X786500Y575688D03*
X786032Y570468D03*
X783500Y649000D03*
X784804Y673304D03*
X779500Y705000D03*
X785000Y892000D03*
X785500Y969700D03*
X796000Y167600D03*
X795500Y163408D03*
X802942Y303250D03*
X791058D03*
X806808D03*
X798000Y400500D03*
X796074Y479000D03*
X803500Y655000D03*
X798000Y706000D03*
X802000Y724000D03*
X801750Y867500D03*
X818000Y240900D03*
X821100Y348480D03*
Y352480D03*
X808500Y363500D03*
X823500Y480000D03*
X814500Y472500D03*
X823500Y556500D03*
X815900Y564000D03*
X819500D03*
X821250Y845750D03*
X810500Y851000D03*
X819000Y868500D03*
X832000Y137500D03*
X826198Y239950D03*
X833555Y262000D03*
X833500Y613000D03*
X835000Y719000D03*
X826500Y743000D03*
X824560Y868560D03*
X856055Y262500D03*
X842555Y262000D03*
X850540Y346070D03*
X844410Y346360D03*
X847500Y352000D03*
X849500Y622000D03*
X846500Y710000D03*
X845500Y865000D03*
X873000Y68500D03*
X870100Y237500D03*
X869544Y226000D03*
X860400Y231000D03*
X860555Y262500D03*
X863820Y363880D03*
X868820D03*
X870500Y444000D03*
Y448000D03*
X857500Y485500D03*
X862500Y621250D03*
X859500Y629500D03*
X872000Y636000D03*
X867500Y655200D03*
X860718Y683684D03*
X877860Y316330D03*
X887950Y359730D03*
X874910Y360160D03*
X879510Y355410D03*
X887940Y380200D03*
X878000Y404500D03*
X876000Y435500D03*
X886300Y443100D03*
X882700D03*
X885000Y438700D03*
X877000Y479500D03*
X876000Y631700D03*
X881000Y710000D03*
X899000Y312500D03*
X898000Y316000D03*
X903480Y324230D03*
X893500Y427000D03*
X893600Y443100D03*
X889900D03*
X903075Y472000D03*
X918420Y449130D03*
X907000Y465050D03*
X917000Y752500D03*
X923000Y51500D03*
X924465Y388465D03*
X936030Y457540D03*
X937000Y489000D03*
X935400Y597300D03*
X939500Y352000D03*
X953500Y348927D03*
X944000Y434000D03*
X958500Y187500D03*
X957990Y191064D03*
X962000Y251500D03*
X965500Y260500D03*
X963500Y256000D03*
X959500Y351688D03*
X965000Y364500D03*
X964000Y354000D03*
X970382Y455872D03*
X961700Y477500D03*
X957500Y585500D03*
X961500D03*
X970750Y703000D03*
X980490Y198827D03*
X982075Y439500D03*
X973015Y453416D03*
X977000Y547500D03*
X982500Y549500D03*
X978000Y554000D03*
X975000Y701000D03*
X1003000Y59500D03*
X988900Y434800D03*
X992690Y466750D03*
X996910Y466560D03*
X994500Y491000D03*
X1003422Y490578D03*
X992000Y505500D03*
X990500Y536500D03*
X998500Y591500D03*
X989000Y659500D03*
Y757150D03*
X1016500Y87500D03*
X1020500Y124500D03*
Y142000D03*
X1014000Y487000D03*
X1007500Y507000D03*
X1008500Y533400D03*
X1013500Y559000D03*
X1016900Y561000D03*
X1017982Y585018D03*
X1007532Y902468D03*
X1033500Y118000D03*
X1025500Y129500D03*
X1033500Y124000D03*
X1037085Y137000D03*
X1023000Y155000D03*
X1028000Y164500D03*
X1023600Y173000D03*
X1031524Y218476D03*
X1033900Y225500D03*
X1027426Y346500D03*
X1023000Y347000D03*
X1031000Y348500D03*
Y355950D03*
X1030000Y403500D03*
X1036500Y581500D03*
X1035000Y594500D03*
X1021000Y588500D03*
X1025500Y657000D03*
X1023500Y727000D03*
X1037000Y734000D03*
X1024387Y738230D03*
X1035000Y800000D03*
Y804500D03*
X1032657Y901500D03*
X1027716Y914784D03*
X1032200Y921500D03*
X1045031Y138031D03*
X1041485Y137409D03*
X1040000Y182000D03*
X1037500Y225500D03*
X1040000Y579000D03*
X1038000Y604000D03*
X1053500Y620500D03*
X1046000Y644000D03*
X1038000Y635000D03*
X1042450Y648500D03*
X1045500Y639500D03*
X1050092Y655052D03*
X1042400Y684500D03*
X1052500Y693000D03*
X1052678Y704084D03*
X1038500Y706500D03*
X1052500Y709000D03*
Y700000D03*
X1041410Y708804D03*
Y704224D03*
X1052648Y712724D03*
X1040208Y745020D03*
X1052500Y773350D03*
X1044000Y763940D03*
X1064000Y80000D03*
X1055500D03*
X1059500D03*
X1068000D03*
Y76000D03*
X1064000D03*
X1059500D03*
X1055500D03*
X1068500Y118500D03*
X1069000Y124500D03*
X1060900Y173534D03*
X1066500Y185500D03*
X1056500Y194000D03*
X1061000Y211500D03*
X1055000Y219284D03*
X1060766Y395426D03*
X1061200Y399000D03*
X1068300Y488700D03*
X1059000Y558190D03*
X1058000Y599500D03*
X1056000Y604000D03*
X1058500Y660900D03*
X1054900D03*
X1070000Y650725D03*
X1058350Y681450D03*
X1068500Y677000D03*
X1054500Y697000D03*
X1068500Y687000D03*
X1066000Y717000D03*
X1059800Y719740D03*
X1054000Y735000D03*
X1056350Y748000D03*
X1063000Y780000D03*
X1072000Y136000D03*
X1074500Y185500D03*
X1072500Y208924D03*
X1078500Y464000D03*
X1080000Y520000D03*
X1081000Y548000D03*
Y544400D03*
X1084599Y544520D03*
X1086000Y556000D03*
X1071500Y589000D03*
X1085000Y661000D03*
X1074000Y677000D03*
X1073500Y672000D03*
X1074000Y683000D03*
X1074500Y694754D03*
X1074426Y687255D03*
X1074389Y691155D03*
X1074000Y699500D03*
X1074148Y711624D03*
X1074600Y707724D03*
X1074000Y703500D03*
X1073384Y722384D03*
X1073000Y730834D03*
Y726444D03*
X1074288Y715534D03*
X1084300Y741874D03*
X1077500Y745374D03*
X1072000Y743500D03*
X1084000Y748099D03*
X1070098Y764500D03*
X1083700Y835725D03*
X1077000Y943075D03*
X1083200Y956500D03*
X1093894Y126500D03*
X1090028D03*
X1092500Y461500D03*
X1098500Y465000D03*
X1089000Y508500D03*
X1100575Y559075D03*
X1098000Y562000D03*
X1091425Y551425D03*
X1093500Y640000D03*
X1094500Y657500D03*
X1091000Y692519D03*
X1090257Y724253D03*
X1087600Y727029D03*
X1094853Y726853D03*
X1095500Y812000D03*
X1097500Y849000D03*
X1089000Y867284D03*
X1099623Y869123D03*
X1097423Y906546D03*
X1093500Y905500D03*
X1110318Y275600D03*
X1111500Y517500D03*
X1107500Y580000D03*
X1114883Y591925D03*
X1106000Y609500D03*
Y605500D03*
X1111500Y718500D03*
X1107000Y763000D03*
X1110300Y790000D03*
X1111834Y813334D03*
X1113500Y824500D03*
X1111000Y836000D03*
X1107160Y843160D03*
X1128000Y288500D03*
X1132300Y288800D03*
X1130000Y361500D03*
X1124327Y465391D03*
X1123500Y521500D03*
X1128149Y525261D03*
X1130928Y527550D03*
X1132000Y562000D03*
X1125600Y570600D03*
X1135000Y597000D03*
X1132222Y593278D03*
X1119487Y588088D03*
X1122353Y590268D03*
X1125000Y603050D03*
X1134000Y613500D03*
X1126000Y627329D03*
X1131000Y631000D03*
X1121500Y621600D03*
X1130490Y627436D03*
X1125041Y631000D03*
X1120500Y729500D03*
X1124000Y729000D03*
X1128430Y749640D03*
X1126642Y785505D03*
X1123200Y783900D03*
X1130030Y820000D03*
X1146500Y267000D03*
X1146000Y258500D03*
X1151000Y264500D03*
X1146500Y275500D03*
X1136100Y288900D03*
X1136450Y294650D03*
X1150640Y359860D03*
X1146640D03*
X1142640D03*
X1151500Y522000D03*
X1143500Y542000D03*
X1147500D03*
X1136075Y559075D03*
X1145900Y579800D03*
X1136500Y592500D03*
X1139632Y594441D03*
X1140500Y589000D03*
X1141100Y585400D03*
X1147400Y729900D03*
X1166000Y232000D03*
X1153700Y267700D03*
X1156100Y316405D03*
Y312795D03*
X1165000Y308175D03*
Y304565D03*
X1161530Y360430D03*
X1157480Y361620D03*
X1157700Y368500D03*
X1160058Y364558D03*
X1155400Y371500D03*
X1164000Y397000D03*
X1168000Y390250D03*
X1166500Y415500D03*
X1155500Y450758D03*
Y446892D03*
X1161000Y541500D03*
X1154000Y589000D03*
X1164500Y628723D03*
X1159075Y630600D03*
X1154847Y630908D03*
X1156377Y627623D03*
X1153500Y784190D03*
X1164500Y857500D03*
X1162000Y960625D03*
X1171000Y232000D03*
X1181427Y251500D03*
X1180677Y256500D03*
X1173777Y290125D03*
X1169777D03*
X1173125Y323716D03*
X1169515D03*
X1184000Y351500D03*
X1174500Y366000D03*
X1182000Y357000D03*
X1174400Y356500D03*
X1178000D03*
X1175125Y370000D03*
X1174500Y404000D03*
X1173500Y422500D03*
Y554000D03*
X1181350Y595450D03*
X1169075Y613500D03*
X1183000Y628000D03*
X1177100Y624750D03*
X1178500Y653100D03*
X1184500Y749500D03*
Y772782D03*
X1173200Y789500D03*
X1177000Y860000D03*
X1169000Y856000D03*
X1181500Y949000D03*
X1186500Y232000D03*
X1188000Y248500D03*
X1192743Y289800D03*
X1188877D03*
X1199685Y344588D03*
X1196075D03*
X1189000Y421500D03*
X1195000Y428000D03*
X1197675Y533125D03*
X1191000Y528000D03*
X1189000Y533825D03*
X1194564Y530936D03*
X1185500Y548075D03*
X1200500Y547925D03*
X1186000Y615500D03*
X1196000Y605800D03*
X1184956Y619272D03*
X1191000Y663000D03*
X1193804Y657175D03*
X1191000Y667000D03*
X1197500Y665500D03*
X1199551Y683968D03*
X1195937Y683849D03*
X1189890Y684053D03*
X1192937Y683911D03*
X1196500Y745500D03*
Y736687D03*
X1192500Y745500D03*
X1192038Y761481D03*
X1188500Y773000D03*
X1184975Y767500D03*
X1194000Y764500D03*
X1190000Y767500D03*
X1196000Y847500D03*
Y874500D03*
X1208500Y202000D03*
X1209000Y212500D03*
X1208000Y231000D03*
X1207500Y239500D03*
X1210800Y379700D03*
X1216000Y390000D03*
X1209500Y404500D03*
X1216500Y439500D03*
X1212500Y436000D03*
X1217000Y452500D03*
X1210000Y507500D03*
X1209500Y514000D03*
X1213100D03*
X1214450Y509000D03*
X1206400Y536800D03*
X1210000D03*
X1201500Y535000D03*
X1205240Y568760D03*
X1207700Y605500D03*
X1208500Y623000D03*
X1204500Y659500D03*
X1203181Y683968D03*
X1206781Y684003D03*
X1213598Y699164D03*
X1216000Y702500D03*
X1206500Y757000D03*
X1213500Y756000D03*
X1202218Y811282D03*
X1211000Y847500D03*
X1208940Y874560D03*
X1227500Y500500D03*
Y504246D03*
X1220500Y513000D03*
X1229500Y533000D03*
X1231632Y537000D03*
X1221500Y539500D03*
X1233000Y554502D03*
X1219200Y564600D03*
X1221500Y633000D03*
X1231450Y677500D03*
X1229000Y716000D03*
Y726500D03*
Y719600D03*
Y740000D03*
X1230219Y747469D03*
X1232000Y738000D03*
X1234000Y747500D03*
X1224500Y757500D03*
X1228547Y772547D03*
Y778453D03*
X1231000Y768500D03*
X1221000Y764750D03*
X1233000Y782500D03*
X1223500Y798500D03*
X1223000Y826500D03*
X1218500Y834500D03*
X1229807Y847000D03*
X1239000Y190500D03*
X1240000Y209449D03*
X1243000Y431500D03*
X1250000Y422000D03*
X1234500Y439000D03*
X1248250Y439250D03*
X1250450Y462000D03*
X1242000Y459000D03*
X1247800Y472750D03*
X1246750Y476250D03*
X1249000Y509500D03*
X1249251Y528688D03*
X1235482Y546982D03*
X1240000Y546500D03*
Y542900D03*
X1240173Y550327D03*
X1250500Y567000D03*
X1241000Y631500D03*
X1237500Y675500D03*
X1239500Y671000D03*
X1235000Y682000D03*
X1244371Y733129D03*
X1236500Y737925D03*
X1243000Y743000D03*
X1241000Y734500D03*
X1240016Y761500D03*
X1238000Y764500D03*
X1249500Y765500D03*
X1248950Y769500D03*
X1238047Y791953D03*
X1240045Y788957D03*
X1241984Y796000D03*
X1243953Y789000D03*
X1240660Y829000D03*
X1235258Y820758D03*
X1257000Y33000D03*
X1260677Y237000D03*
X1264177Y233500D03*
X1256000Y252000D03*
X1262558Y254942D03*
X1261677Y241500D03*
Y245500D03*
X1264500Y260000D03*
X1254944Y268567D03*
X1263000Y278500D03*
X1250677Y287500D03*
Y283500D03*
X1254944Y272433D03*
X1260577Y299968D03*
Y296102D03*
X1253477Y312800D03*
X1253577Y308800D03*
X1253177Y320500D03*
Y324500D03*
X1265000Y426500D03*
X1253000Y511000D03*
X1251500Y531500D03*
X1260500Y546400D03*
X1263500Y550000D03*
X1258000Y555400D03*
X1255000Y609300D03*
X1266500Y617500D03*
X1265000Y647500D03*
X1257500Y635500D03*
X1265000Y661000D03*
Y657000D03*
X1265500Y652500D03*
X1257100Y664300D03*
X1263121Y678621D03*
X1259000Y678950D03*
X1262300Y670700D03*
X1266000Y665600D03*
X1262500Y699825D03*
X1253500Y778465D03*
X1257950Y809250D03*
X1279500Y150500D03*
X1276500Y234000D03*
X1267677Y232500D03*
X1280500Y338000D03*
Y404550D03*
X1280000Y420500D03*
X1272500Y466600D03*
X1274500Y606000D03*
X1278500Y603500D03*
X1271000Y617500D03*
X1279340Y618660D03*
X1272451Y642500D03*
X1272502Y638900D03*
X1281268Y661780D03*
X1268805Y655405D03*
X1282500Y669561D03*
X1273702Y667662D03*
X1275885Y670525D03*
X1267500Y675000D03*
Y684878D03*
X1281500Y713000D03*
X1279000Y746575D03*
X1267500Y783000D03*
X1269500Y835000D03*
X1299500Y236000D03*
X1292500Y402000D03*
X1289000Y415500D03*
X1285700Y529700D03*
X1293960Y528740D03*
X1294600Y524200D03*
X1291300Y540900D03*
X1294000Y587500D03*
X1288335Y594048D03*
X1287482Y590500D03*
X1293500Y593000D03*
X1285557Y585000D03*
X1289570Y597430D03*
X1284825Y621500D03*
X1294000Y628000D03*
X1299000Y641500D03*
X1296000Y638500D03*
X1290500Y635500D03*
X1286500Y652500D03*
X1297500Y665000D03*
X1289500Y669000D03*
X1284490Y710936D03*
X1296500Y830782D03*
X1306000Y43000D03*
X1304050Y296500D03*
X1307500Y320500D03*
X1308000Y311000D03*
X1312750Y314000D03*
X1306000Y329000D03*
Y334500D03*
Y338500D03*
X1311000Y463500D03*
X1302000Y475000D03*
X1304700Y536000D03*
X1302500Y559500D03*
X1307000Y573412D03*
X1306817Y592412D03*
X1310500Y625000D03*
X1312000Y645784D03*
X1310425Y660062D03*
X1311100Y656400D03*
X1304400Y661400D03*
X1311700Y681500D03*
X1312115Y672000D03*
X1311000Y677284D03*
X1311300Y687500D03*
X1313500Y710000D03*
X1305000Y739750D03*
X1308100Y748200D03*
X1312500Y838000D03*
X1305000Y850500D03*
X1312000D03*
X1314500Y921500D03*
X1322500Y299000D03*
X1324000Y290500D03*
X1322500Y337000D03*
X1317000Y336000D03*
X1330500Y441000D03*
X1332000Y459250D03*
X1323500Y452500D03*
X1326617Y594412D03*
X1325950Y599000D03*
X1329317Y626512D03*
X1328000Y649000D03*
X1328968Y679684D03*
X1323500Y702000D03*
X1322000Y705500D03*
X1325250Y834250D03*
X1316500Y839000D03*
X1317000Y850500D03*
X1318113Y846371D03*
X1339000Y54000D03*
X1347000Y48000D03*
X1342500Y51000D03*
X1333100Y58600D03*
X1343500Y112000D03*
X1336500Y270874D03*
X1339000Y274000D03*
X1339500Y305500D03*
X1341873Y344873D03*
X1335000Y443250D03*
X1335317Y575412D03*
X1342648Y612412D03*
X1347617Y610412D03*
X1334500Y636000D03*
Y669000D03*
X1352000Y85500D03*
X1349500Y112000D03*
X1350000Y276500D03*
X1350084Y296500D03*
X1353000Y390000D03*
Y402000D03*
X1362500Y459000D03*
X1353500Y466500D03*
X1351000Y455750D03*
X1356817Y579012D03*
X1364617Y592912D03*
X1360200Y614800D03*
X1353517Y627512D03*
X1357300Y617700D03*
X1379500Y274500D03*
X1381500Y292000D03*
X1376000D03*
X1379500Y314000D03*
X1370500Y356500D03*
X1374500Y462800D03*
X1367617Y570012D03*
X1390004Y122600D03*
X1384500Y274500D03*
Y331500D03*
G54D47*
X1379862Y108465D03*
Y119095D03*
G54D43*
X1258504Y329331D03*
Y368701D03*
G54D42*
X1224016Y386221D03*
G54D12*
X21220Y373228D03*
X96890D03*
X157480Y283071D03*
X220472D03*
G54D18*
X121890Y269528D03*
X131890D03*
X141890D03*
X1346396Y21656D03*
X1338526D03*
X1346396Y29526D03*
X1362146Y21656D03*
X1354271D03*
X1362146Y29526D03*
X1354271D03*
X1377896Y21656D03*
X1370021D03*
X1377896Y29526D03*
X1370021D03*
X1385766Y21656D03*
Y29526D03*
G54D19*
X121000Y545500D03*
X146364Y296000D03*
X156500Y939500D03*
X162000D03*
X168000Y575000D03*
Y580000D03*
X178000Y590000D03*
X167500Y939500D03*
X172500D03*
X177500D03*
X182000D03*
X188000D03*
X193500D03*
X199500D03*
X207100Y703600D03*
X222000Y703500D03*
X224000Y875000D03*
X225500Y879500D03*
X225000Y920500D03*
X232000Y921000D03*
X227500Y957500D03*
Y963500D03*
X247500Y883000D03*
X243000D03*
X246968Y957784D03*
X233468Y957284D03*
X239968Y957784D03*
X246968Y963784D03*
X239968D03*
X233468D03*
X259000Y211000D03*
Y206000D03*
X262500Y208500D03*
X252000Y883000D03*
X256500D03*
X261000D03*
X265500D03*
X252000Y957500D03*
X252500Y963500D03*
X281800Y183700D03*
Y188500D03*
X281900Y178500D03*
X278500Y965000D03*
X277500Y969500D03*
X272500D03*
X268000D03*
X296000Y105000D03*
X285800Y180800D03*
X285600Y186100D03*
X285500Y330000D03*
X286000Y336000D03*
X306000Y105000D03*
X301000D03*
X310929Y257500D03*
X320500Y11000D03*
X316000D03*
X324000Y24000D03*
Y19500D03*
Y15000D03*
X330500Y38500D03*
Y33500D03*
X315929Y253000D03*
Y257500D03*
X322429Y349300D03*
X344000Y27000D03*
X336000D03*
X337500Y102000D03*
X335645Y445630D03*
X349000Y38500D03*
Y33500D03*
X351929Y266000D03*
X362500Y608500D03*
X355500D03*
Y614000D03*
X362500D03*
X370500Y72100D03*
X376500Y608500D03*
X369500D03*
Y614000D03*
X376500D03*
X393800Y25100D03*
X389300Y20100D03*
X393800D03*
X384800Y25100D03*
X389300D03*
X384800Y20100D03*
X391000Y35500D03*
X395500D03*
X393900Y30400D03*
X389400D03*
X384900D03*
X386000Y53000D03*
X381500D03*
Y58000D03*
X398300Y20100D03*
Y25100D03*
X400000Y35500D03*
X398400Y30400D03*
X398000Y39500D03*
X445395Y317610D03*
X432678Y827300D03*
X430778Y864000D03*
X453878Y824900D03*
X456278Y866500D03*
X467000Y118500D03*
X482429Y139000D03*
X482778Y832000D03*
X482278Y867500D03*
X495000Y883000D03*
X501000Y876000D03*
X499000Y883000D03*
X516000Y134000D03*
X519929Y135500D03*
X521055Y528500D03*
Y533500D03*
X516555Y528500D03*
Y533500D03*
X526055D03*
X526000Y524500D03*
Y529000D03*
X521000Y524000D03*
X521055Y544000D03*
Y548900D03*
X516555Y543500D03*
X516655Y548900D03*
X521055Y538500D03*
X516555Y539000D03*
X526055Y538500D03*
Y544000D03*
Y548900D03*
X516500Y556000D03*
X591000Y253500D03*
Y262500D03*
X586000Y267000D03*
Y262500D03*
X591000Y258000D03*
X586150Y383000D03*
X586200Y378500D03*
X581950Y383000D03*
X582000Y378500D03*
X590500Y383000D03*
X586150Y396000D03*
X590500D03*
X581950D03*
X586150Y409500D03*
X581950D03*
X590500D03*
X582700Y431500D03*
X590500Y423500D03*
X586150D03*
X587000Y431500D03*
X578500D03*
X581950Y423500D03*
X582200Y439500D03*
X578000D03*
X586500D03*
X593500Y648500D03*
Y659500D03*
Y654000D03*
X595500Y253500D03*
Y258000D03*
X610000Y415500D03*
Y434000D03*
Y428500D03*
Y422000D03*
X610100Y439500D03*
X602500Y465900D03*
X608000Y465800D03*
X602500Y470100D03*
X608000Y470300D03*
X601000Y543000D03*
X599500Y648500D03*
Y654000D03*
Y659500D03*
X609500Y778500D03*
X603000D03*
Y785000D03*
X609000Y870000D03*
X604000Y877500D03*
X609211Y877611D03*
X614200Y415500D03*
X614500Y434000D03*
X614200Y422000D03*
Y428500D03*
X614300Y439500D03*
X620000Y465800D03*
X613500D03*
X626500D03*
X613500Y470000D03*
X620000D03*
X626500D03*
Y557350D03*
X637500Y367900D03*
X630500Y368500D03*
X642000D03*
X647500D03*
X653500D03*
X659500D03*
X645500Y481000D03*
X674666Y82002D03*
X670998Y116010D03*
X665000Y368500D03*
X670000Y395000D03*
X670500Y414000D03*
X685898Y133380D03*
X682418Y129980D03*
X685000Y150500D03*
X701949Y118331D03*
X701828Y129550D03*
X698500Y132500D03*
X697248Y128000D03*
X719500Y185600D03*
X725000Y189000D03*
X720000Y849000D03*
X721900Y852750D03*
X730748Y99500D03*
X740000Y109534D03*
X732248Y140000D03*
X731716Y156500D03*
X736000Y142000D03*
X740000Y681000D03*
X740500Y755000D03*
X739900Y760000D03*
X757000Y435500D03*
X752100Y435600D03*
X751500Y431000D03*
X756500D03*
X757802Y474000D03*
X773000Y339500D03*
X761600Y435600D03*
X761500Y431000D03*
X766000D03*
X770000Y677000D03*
Y681500D03*
X767000Y845000D03*
X773000Y917000D03*
Y921500D03*
Y927000D03*
X767500D03*
X771000Y958500D03*
X766600D03*
X762100Y958600D03*
X771500Y963500D03*
X767100D03*
X762600Y963600D03*
X771400Y968900D03*
X767000D03*
X762500Y969000D03*
X777500Y339500D03*
X782400Y339400D03*
X782600Y411000D03*
X792000Y356500D03*
X801500Y573000D03*
X819000Y473000D03*
X829500Y373500D03*
Y380000D03*
Y385500D03*
X848600Y517100D03*
X843100Y517000D03*
X843200Y512800D03*
X843300Y507900D03*
X848800Y508000D03*
X848700Y512900D03*
X854500Y778000D03*
X850000D03*
X854500Y783000D03*
X850000D03*
X858500Y656500D03*
X879736Y290000D03*
X875500Y290500D03*
X878500Y294178D03*
X884000Y396500D03*
X879500D03*
X889000Y617000D03*
X895000Y96000D03*
X899500Y92500D03*
X899000Y405500D03*
X894000D03*
X899000Y410500D03*
X894000D03*
X895000Y617500D03*
X930500Y536500D03*
X943500Y488000D03*
X966000Y209500D03*
X961000Y212500D03*
X963500Y488000D03*
Y536500D03*
Y654500D03*
X958000D03*
Y659500D03*
X963500D03*
X969000Y655100D03*
Y659500D03*
X981000Y386500D03*
X985000Y388000D03*
X980500Y391000D03*
X984500Y392500D03*
X974500Y655100D03*
Y659500D03*
X1004500Y84000D03*
X1013500D03*
X1009000D03*
X1016500Y75500D03*
X1011500Y642000D03*
Y648000D03*
X1022500Y51500D03*
X1034500D03*
X1028000D03*
X1021000Y75500D03*
X1033000Y290000D03*
X1027500D03*
X1027700Y294200D03*
X1033200D03*
X1035500Y825500D03*
Y830000D03*
X1053000Y228000D03*
X1046000Y290000D03*
X1039500D03*
X1039700Y294200D03*
X1046200D03*
X1040000Y825500D03*
X1044500D03*
X1049000D03*
X1053400D03*
X1040000Y830000D03*
X1057000Y229500D03*
X1056716Y224500D03*
X1060000Y929500D03*
X1079000Y434000D03*
X1085000D03*
X1079100Y429000D03*
X1101500Y461500D03*
X1102500Y762500D03*
X1097500D03*
X1102500Y767400D03*
X1097500D03*
X1093000Y766500D03*
X1097500Y797500D03*
X1106600Y753000D03*
X1134000Y229000D03*
X1128500D03*
X1129000Y502500D03*
X1123500D03*
Y507500D03*
X1129000D03*
X1135500D03*
Y502500D03*
X1141000Y507500D03*
Y502500D03*
X1161500Y222000D03*
X1166500D03*
X1160500Y242000D03*
Y246500D03*
X1165000Y242000D03*
Y246500D03*
X1171000Y222000D03*
X1176000D03*
X1169000Y398000D03*
X1171000Y394000D03*
X1170500Y461000D03*
X1173100Y499200D03*
X1182000Y816000D03*
X1181500Y820500D03*
X1177000D03*
X1199100Y226600D03*
X1194900D03*
X1195000Y422500D03*
X1194000Y484000D03*
X1189500D03*
X1194000Y488500D03*
X1189500D03*
Y492900D03*
X1194000Y493000D03*
X1188500Y500000D03*
X1195920Y753700D03*
X1204000Y206000D03*
X1208500Y207000D03*
X1204000Y210500D03*
Y215000D03*
X1207500Y225000D03*
X1203300Y226600D03*
X1217000Y537000D03*
X1216500Y710125D03*
X1249300Y166000D03*
X1240600Y167000D03*
X1240700Y171200D03*
X1240800Y179800D03*
X1240700Y175500D03*
Y184000D03*
X1241000Y219000D03*
X1239500Y227500D03*
X1242000Y223500D03*
X1244000Y227500D03*
X1246000Y263500D03*
X1263000Y717000D03*
X1287500Y428000D03*
X1308500Y771500D03*
X1303000D03*
X1314000D03*
X1358500Y346500D03*
Y351000D03*
X1354000D03*
Y346500D03*
X1354500Y480500D03*
Y475000D03*
X1360500D03*
Y480500D03*
X1354500Y486500D03*
X1360500D03*
X1360000Y631500D03*
X1355500Y631000D03*
X1358000Y626000D03*
X1357500Y635500D03*
X1351000Y677000D03*
Y672000D03*
X1355000Y674500D03*
X1354500Y669000D03*
X1371500Y254000D03*
X1366000D03*
X1371500Y264000D03*
X1366000D03*
X1371500Y259500D03*
X1366000D03*
G54D22*
X180118Y729409D03*
Y739409D03*
X200118Y729409D03*
X190118D03*
X210118D03*
X220118D03*
X250118D03*
X240118D03*
G54D36*
X599941Y70118D03*
X607933D03*
X595905Y80118D03*
X603897D03*
X611889D03*
X615925Y70118D03*
X623917D03*
X627953Y80118D03*
X631909Y70118D03*
X639901D03*
X635945Y80118D03*
X643937D03*
G54D31*
X545079Y290355D03*
X560829D03*
X549014Y298230D03*
X556889Y308070D03*
X552954Y315945D03*
X549014Y308070D03*
X576574Y290355D03*
X564764Y298230D03*
X572639Y308070D03*
X568699Y315945D03*
X592324Y290355D03*
X580514Y298230D03*
X588384Y308070D03*
X584449Y315945D03*
X608069Y290355D03*
X596259Y298230D03*
X604134Y308070D03*
X600199Y315945D03*
X627754Y298230D03*
X623819Y290355D03*
X612009Y298230D03*
X619884Y308070D03*
X615944Y315945D03*
X643504Y298230D03*
X639569Y290355D03*
X635629Y308070D03*
X631694Y315945D03*
X659254Y298230D03*
X655314Y290355D03*
X651379Y308070D03*
X647439Y315945D03*
X674999Y298230D03*
X671064Y290355D03*
X667124Y308070D03*
X663189Y315945D03*
X690749Y298230D03*
X686809Y290355D03*
X682874Y308070D03*
X678939Y315945D03*
X706494Y298230D03*
X702559Y290355D03*
X698624Y308070D03*
X694684Y315945D03*
X722244Y298230D03*
X718309Y290355D03*
X726179Y315945D03*
X714369Y308070D03*
X710434Y315945D03*
X737994Y298230D03*
X734054Y290355D03*
X741929Y315945D03*
X730119Y308070D03*
X753739Y298230D03*
X749804Y290355D03*
X757679Y315945D03*
X745864Y308070D03*
X769489Y298230D03*
X765549Y290355D03*
X773424Y315945D03*
X761614Y308070D03*
X785234Y298230D03*
X781299Y290355D03*
X789174Y315945D03*
X777364Y308070D03*
X800984Y298230D03*
X797049Y290355D03*
X804919Y315945D03*
X793109Y308070D03*
X816734Y298230D03*
X812794Y290355D03*
X820669Y315945D03*
X808859Y308070D03*
X840354Y298230D03*
X836419Y290355D03*
X832479Y298230D03*
X840354Y308070D03*
X836419Y315945D03*
X832479Y308070D03*
X856104Y298230D03*
X852164Y290355D03*
X848229Y298230D03*
X844289Y290355D03*
X856104Y308070D03*
X852164Y315945D03*
X844289D03*
X871849Y298230D03*
X867914Y290355D03*
X863974Y298230D03*
X871849Y308070D03*
X867914Y315945D03*
X863974Y308070D03*
G54D39*
X1066929Y43267D03*
X1057086D03*
X1074803D03*
X1272441Y7087D03*
X1299213D03*
G54D41*
X1224016Y180709D03*
G54D24*
X200000Y401500D03*
Y411500D03*
Y421500D03*
X216500Y401500D03*
Y411500D03*
Y421500D03*
X945197Y380000D03*
X968819D03*
X1296000Y319500D03*
Y329500D03*
X1367067Y42323D03*
Y78544D03*
X1392657Y42323D03*
Y78544D03*
G54D28*
X402953Y23622D03*
X413189D03*
X423425D03*
G54D33*
X590315Y9134D03*
Y19134D03*
X649527Y9134D03*
Y19134D03*
Y29134D03*
G54D15*
X35435Y373228D03*
X82675D03*
G54D44*
X1272677Y349016D03*
G54D29*
X404920Y334054D03*
X412794D03*
Y341928D03*
Y365550D03*
Y357676D03*
Y377363D03*
Y385237D03*
Y400985D03*
Y393111D03*
Y416733D03*
Y408859D03*
Y424607D03*
X399555Y438500D03*
X420668Y334054D03*
X428542Y345865D03*
X416615Y349930D03*
X428542Y361613D03*
Y369487D03*
Y353739D03*
X416731D03*
X428542Y385237D03*
Y400985D03*
X424605D03*
X428542Y397048D03*
X420668Y400985D03*
X428523Y416683D03*
X423555Y431500D03*
X434448Y320783D03*
X432585Y345850D03*
X440353Y369487D03*
X444290Y365550D03*
Y357676D03*
Y385237D03*
Y377363D03*
X440353Y381300D03*
X436416Y377363D03*
X432479Y381300D03*
X440353Y400985D03*
Y389174D03*
X432479Y400985D03*
Y397048D03*
Y393111D03*
Y389174D03*
X444323Y416883D03*
X436523Y416683D03*
X442535Y426770D03*
X434723Y426283D03*
X460040Y330117D03*
X456103Y341928D03*
Y365550D03*
Y357676D03*
X460040Y369487D03*
Y361613D03*
X448227Y369487D03*
Y361613D03*
Y353739D03*
X456103Y385237D03*
Y377363D03*
X460040Y381300D03*
X448227D03*
X460040Y389174D03*
X448227D03*
X456103Y400985D03*
X460040D03*
X456103Y393111D03*
X460040D03*
Y397048D03*
X448227Y400985D03*
Y393111D03*
X456103Y412796D03*
X460023Y408883D03*
X450725Y425460D03*
X467914Y330117D03*
X475788Y349802D03*
Y341928D03*
X467914Y349802D03*
X463977Y341928D03*
X475788Y369487D03*
Y361613D03*
Y357676D03*
X467914Y369487D03*
Y361613D03*
Y365550D03*
Y357676D03*
Y353739D03*
X463977Y365550D03*
Y357676D03*
Y385237D03*
X475788Y381300D03*
Y377363D03*
X467914Y385237D03*
Y377363D03*
Y381300D03*
X463977Y377363D03*
X475788Y400985D03*
Y397048D03*
Y393111D03*
X471851D03*
Y397048D03*
X475788Y389174D03*
X467914Y400985D03*
Y397048D03*
Y393111D03*
Y389174D03*
X463977Y393111D03*
Y397048D03*
X471851Y412796D03*
X475788Y424607D03*
X493855Y312700D03*
X488155Y315700D03*
X490455Y319200D03*
X481255Y320000D03*
X491536Y334054D03*
X479725Y330117D03*
X479655Y322500D03*
X491536Y341928D03*
X479725Y337991D03*
Y369487D03*
Y361613D03*
X487643Y361523D03*
X491500Y353500D03*
X491536Y385237D03*
Y377363D03*
X479725Y381300D03*
X491536Y400985D03*
Y393111D03*
X479725Y397048D03*
Y389174D03*
X491536Y416733D03*
Y408859D03*
X487599Y416733D03*
X483662Y408859D03*
X487599Y404922D03*
X479725Y412796D03*
X491536Y420670D03*
Y424607D03*
X483662D03*
X487599D03*
X505678Y310921D03*
X506000Y317500D03*
X498855Y311100D03*
X498955Y316900D03*
X505523Y332086D03*
X499410Y322243D03*
X511500Y348000D03*
X511455Y338700D03*
X505523Y363582D03*
X507955Y356100D03*
X505523Y371456D03*
X503347Y381300D03*
Y397048D03*
Y389174D03*
X499410Y416733D03*
Y412796D03*
Y408859D03*
X503347D03*
Y404922D03*
X495473Y416733D03*
Y412796D03*
Y408859D03*
X499410Y420670D03*
Y424607D03*
X503347Y420670D03*
X495473Y424607D03*
Y420670D03*
X1020500Y882500D03*
Y887000D03*
X1011966Y893534D03*
X1020282Y911218D03*
X1034000Y155000D03*
X1021468Y866968D03*
X1032600Y867657D03*
X1031500Y884500D03*
X1035216Y884468D03*
X1035000Y888500D03*
Y880500D03*
Y970000D03*
X1039468Y155284D03*
X1048968D03*
X1053500Y153000D03*
X1044000D03*
X1048968Y150784D03*
X1039500Y151000D03*
X1048968Y159284D03*
X1039500Y159500D03*
X1053500Y157500D03*
X1044000D03*
X1045968Y185500D03*
X1039000Y884500D03*
X1051000Y883600D03*
Y888500D03*
X1065000Y154000D03*
X1057968Y155284D03*
X1058000Y150500D03*
Y159500D03*
X1060509Y177126D03*
X1058000Y889500D03*
Y902500D03*
Y896000D03*
X1055000Y970000D03*
X1084988Y154203D03*
X1080500Y153500D03*
X1077500Y150000D03*
X1085150Y158400D03*
X1075000Y970000D03*
X1105000D03*
X1125000D03*
X1145000D03*
X1175000D03*
X1195000D03*
X1215000D03*
X1259968Y444284D03*
X1260000Y448500D03*
X1264500Y446500D03*
X1260000Y440000D03*
X1264500Y442000D03*
X1257468Y478500D03*
X1278500Y448500D03*
Y444000D03*
X1274000Y447000D03*
X1269468Y444284D03*
Y448284D03*
X1278500Y439500D03*
X1269468Y439784D03*
X1274000Y442000D03*
X1270000Y477000D03*
X1288000Y442000D03*
X1292500Y441000D03*
X1318000Y369500D03*
Y375500D03*
Y381500D03*
X1330000Y428000D03*
X1331500Y432500D03*
X1344000Y434500D03*
X1340200D03*
Y438300D03*
X1343900Y438500D03*
X1343000Y466500D03*
G54D10*
X8590Y318590D03*
X4500Y329297D03*
Y349297D03*
Y369297D03*
Y389297D03*
Y409297D03*
Y429297D03*
Y449297D03*
Y469297D03*
Y489297D03*
Y509297D03*
Y529297D03*
Y549297D03*
Y569297D03*
Y589297D03*
Y609297D03*
Y629297D03*
Y649297D03*
Y669297D03*
Y689297D03*
Y709297D03*
Y729297D03*
Y749297D03*
Y769297D03*
Y789297D03*
Y809297D03*
Y829297D03*
Y849297D03*
X8442Y847311D03*
X4500Y869297D03*
Y889297D03*
Y909297D03*
Y929297D03*
Y949297D03*
Y969297D03*
X20000Y380000D03*
Y440000D03*
Y460000D03*
Y480000D03*
Y500000D03*
X50395Y384679D03*
X40945Y384710D03*
X48820Y412435D03*
X39370Y412673D03*
X40054Y823970D03*
X36004Y839500D03*
X38804Y906220D03*
X41500Y941500D03*
X46500Y944500D03*
X59840Y384679D03*
X67715Y412518D03*
X58270Y412485D03*
X60304Y663220D03*
X64304Y698720D03*
X63304Y706720D03*
X64272Y736004D03*
X55304Y849720D03*
X78740Y384915D03*
X69290Y384865D03*
X77165Y412590D03*
X76804Y662720D03*
X73804Y699720D03*
X81304Y710220D03*
X76272Y762504D03*
X77804Y773720D03*
X71804Y789720D03*
X73772Y822004D03*
X69804Y835720D03*
X83838Y848133D03*
X76804Y847720D03*
X81804Y888720D03*
X72770Y906488D03*
X95304Y663720D03*
X97737Y698653D03*
X96060Y762476D03*
X100804Y774720D03*
X99804Y799720D03*
X85804Y816220D03*
X87804Y835720D03*
X98304Y888220D03*
X97804Y940720D03*
X112654Y314453D03*
X111304Y663720D03*
X111907Y698617D03*
X115804Y798720D03*
X101804Y940720D03*
X112900Y988500D03*
X132500Y312500D03*
X124500Y316000D03*
X122874Y354709D03*
X132804Y894220D03*
X134874Y354709D03*
X147374D03*
X149100Y661100D03*
X143010Y676400D03*
X162595Y296709D03*
X153437Y320458D03*
X155874Y310209D03*
X152995Y329119D03*
X159674Y328609D03*
X159774Y320709D03*
X158874Y354709D03*
X166875Y678285D03*
X153500Y690275D03*
X163000Y901000D03*
X158000D03*
X172285Y296964D03*
X181889Y297303D03*
X183374Y328709D03*
X171874D03*
X171295Y320709D03*
X180315Y321209D03*
X170374Y354709D03*
X172040Y688960D03*
X181000Y901000D03*
X174500Y901500D03*
X168500Y901000D03*
X197245Y296571D03*
X196063Y319209D03*
X192874Y326209D03*
Y337907D03*
X189000Y347600D03*
X185000Y533562D03*
X185305Y521100D03*
X195865Y552940D03*
X189500Y573500D03*
X198000Y785000D03*
X191875Y803125D03*
X188000Y901000D03*
X197000D03*
Y897000D03*
X207086Y297418D03*
X205511Y320709D03*
X214960Y321044D03*
X207773Y516562D03*
X208305Y548670D03*
Y536320D03*
X201000Y625500D03*
X212500Y786000D03*
X204500Y817500D03*
X205500Y901000D03*
Y897000D03*
X217295Y296709D03*
X232500Y425000D03*
X231500Y898500D03*
X236500Y574000D03*
X240000Y829250D03*
X236500Y866000D03*
X261500Y188900D03*
X256300Y188800D03*
X258800Y184200D03*
X261400Y179800D03*
X255800Y179600D03*
X258500Y608500D03*
Y613500D03*
X253500Y608500D03*
X253555Y613500D03*
X261500Y857500D03*
X262178Y976000D03*
X261178Y981040D03*
X268300Y219800D03*
X273000Y674000D03*
X269000Y921500D03*
X274000D03*
X273678Y958000D03*
X268178Y955500D03*
X285678Y995500D03*
X293178D03*
X299500Y5500D03*
X299300Y84200D03*
X311500Y153000D03*
X299000Y148000D03*
X307129Y143000D03*
X305029Y147700D03*
X304300Y160200D03*
X304100Y167000D03*
X311300D03*
X312500Y159100D03*
X305429Y219400D03*
Y223000D03*
X311500Y272000D03*
X307500Y299000D03*
X311429Y334500D03*
X307429Y336000D03*
Y331500D03*
X298662Y479783D03*
X306155Y497700D03*
X301178Y995500D03*
X309678D03*
X321000Y29000D03*
Y33500D03*
Y38000D03*
Y57000D03*
Y52500D03*
Y48000D03*
Y42500D03*
Y61500D03*
X316900Y65900D03*
X320500Y66000D03*
X330250Y80000D03*
X317660Y96400D03*
X330900Y134500D03*
X329929Y128500D03*
X325929Y127700D03*
X319014Y152977D03*
X328700Y154400D03*
X328629Y146800D03*
X330400Y141600D03*
X318200Y159100D03*
X329929Y241500D03*
X316000Y271500D03*
X317195Y493280D03*
X317255Y514170D03*
X320338Y507683D03*
X324678Y995500D03*
X317178D03*
X336700Y4300D03*
X341200D03*
X346000Y4400D03*
X338000Y127500D03*
X337400Y134500D03*
X334000Y147600D03*
X345929Y183000D03*
X340679Y204900D03*
X332429Y210000D03*
X346404Y260000D03*
X338500Y397500D03*
X336375Y452870D03*
X343688Y509533D03*
X340715Y545840D03*
X339500Y936500D03*
X333500Y954000D03*
X341178Y996000D03*
X332678Y995500D03*
X355000Y4400D03*
X350500D03*
X360400D03*
X362500Y64000D03*
X352500Y113000D03*
X357394Y131496D03*
X348429Y130000D03*
X353929Y128500D03*
X351429Y126500D03*
X362009Y142520D03*
Y148819D03*
Y155119D03*
X362036Y170876D03*
X362034Y161406D03*
X353085Y187485D03*
X355040Y180000D03*
X362017Y183492D03*
X354540Y199000D03*
X353300Y218400D03*
X352429Y279000D03*
X357929Y277000D03*
X357661Y434216D03*
X364055Y428500D03*
X361055Y431500D03*
X364015Y468450D03*
X364055Y512000D03*
X351815Y546880D03*
X364000Y869500D03*
X358268Y995500D03*
X348678Y996000D03*
X364900Y4400D03*
X369400D03*
X370000Y51000D03*
Y55500D03*
Y60000D03*
X368307Y133071D03*
X371458Y142520D03*
X377765Y155146D03*
X374589Y155110D03*
X371455Y148854D03*
X377757Y145670D03*
X365186Y170876D03*
X377732Y167703D03*
X377718Y161417D03*
X371470Y167741D03*
X371489Y161411D03*
X365186Y177175D03*
X368320Y183460D03*
X377741Y177188D03*
X377731Y180302D03*
X371457Y173978D03*
X368336Y189755D03*
X368307Y196062D03*
Y202361D03*
X377755D03*
Y199211D03*
Y196062D03*
Y192912D03*
Y189763D03*
X374607Y218110D03*
X374606Y211810D03*
X366000Y277500D03*
X372055Y364000D03*
X375055Y444500D03*
X378255Y471840D03*
X367555Y545500D03*
X380000Y872000D03*
X371938Y922438D03*
X377953Y995725D03*
X390355Y139371D03*
X380920Y139370D03*
X384055Y155117D03*
X396653D03*
X384093Y151968D03*
X393519Y151990D03*
X384056Y145670D03*
X390355D03*
X396655D03*
X384055Y158266D03*
X396653D03*
X390354Y167715D03*
X396653D03*
X384032Y167703D03*
X380944Y161417D03*
X387219Y158290D03*
X390392Y186614D03*
X384055Y186613D03*
X396654Y186614D03*
X396653Y174015D03*
Y180314D03*
X387204Y177164D03*
X384032Y174003D03*
X384055Y202361D03*
X393503Y205510D03*
X396654Y202362D03*
X396653Y205511D03*
Y199211D03*
X384055Y192912D03*
Y196062D03*
X396653Y192912D03*
X393503Y211809D03*
X380906Y211810D03*
X396654D03*
X396653Y208660D03*
X393503D03*
X390354Y218109D03*
Y221259D03*
Y224408D03*
X391000Y238500D03*
X394929Y247000D03*
X388885Y471100D03*
X389000Y604000D03*
X395500Y867000D03*
X396500Y910500D03*
X383500Y938500D03*
X389763Y996085D03*
X399783Y136237D03*
X406102Y155117D03*
X412402Y155118D03*
X412401Y151967D03*
X399819Y151950D03*
X406110Y145660D03*
X402954Y145670D03*
X402952Y167715D03*
X409251D03*
X412401Y158267D03*
X406102D03*
X402977Y174003D03*
X402952Y186613D03*
X409251D03*
X409288Y180315D03*
X402952Y180314D03*
X409251Y174015D03*
X412401Y205510D03*
X402952Y192912D03*
X409251D03*
X402953Y211810D03*
X412402D03*
X399803Y218109D03*
Y221259D03*
Y208660D03*
X409929Y245400D03*
X403155Y437600D03*
X410500Y885500D03*
X401500Y994500D03*
X421851Y142520D03*
X415552D03*
X428151D03*
X428149Y170865D03*
X421876Y167705D03*
X415575Y167703D03*
X428149Y183463D03*
Y177164D03*
X421876Y174005D03*
Y180304D03*
Y186603D03*
X415551Y186614D03*
X415587Y180315D03*
X415551Y174015D03*
X424999Y199211D03*
X428149D03*
X424999Y202361D03*
X428149D03*
X421876Y192902D03*
X428149Y192912D03*
X415551D03*
X418701Y211810D03*
X425001D03*
X420429Y246400D03*
X416500Y284800D03*
X422500Y271501D03*
X428542Y334054D03*
X425178Y798000D03*
X418278Y828000D03*
Y840000D03*
X418500Y857500D03*
X418278Y854000D03*
Y846500D03*
X419500Y914000D03*
X425000Y994500D03*
X437598Y148818D03*
Y155118D03*
X434450Y142520D03*
X431299Y170865D03*
X437598Y167716D03*
Y161417D03*
X431299Y183463D03*
X434449Y180314D03*
Y174015D03*
X431299Y177164D03*
X434448Y186613D03*
X431299D03*
X434414Y205514D03*
X434449Y199212D03*
Y192913D03*
Y211810D03*
X436500Y241000D03*
X439000Y254500D03*
X440500Y267000D03*
X444255Y283700D03*
X440353Y330117D03*
X444290Y341928D03*
X432178Y798000D03*
X438178Y798500D03*
X444678Y798400D03*
X442278Y846000D03*
X431500Y886000D03*
X437678D03*
X443178D03*
X435678Y996000D03*
X443178D03*
X450929Y118000D03*
X458429Y185000D03*
X455054Y179475D03*
X459500Y290100D03*
X448227Y330117D03*
X458685Y425710D03*
X456178Y798000D03*
X452978Y805400D03*
X455278Y846000D03*
X451278D03*
X459278D03*
X451178Y886000D03*
X460678D03*
X457578Y879700D03*
X458678Y996000D03*
X450178D03*
X471290Y118361D03*
X477291Y147500D03*
X477900Y153600D03*
X469429Y172500D03*
Y165590D03*
X473131Y169131D03*
X477429Y162500D03*
X477929Y158000D03*
X469429Y179500D03*
X465679Y192600D03*
X469155Y297800D03*
X474755Y308300D03*
X464200Y307838D03*
X466655Y425340D03*
X472055Y425000D03*
X475678Y798500D03*
X463178D03*
X469178D03*
X467278Y846000D03*
X468178Y886000D03*
X472178D03*
X474178Y995500D03*
X466178Y996000D03*
X490100Y162100D03*
X492555Y431250D03*
X482178Y886000D03*
X489678Y995500D03*
X482178D03*
X503929Y127500D03*
X499629Y178400D03*
X498855Y302851D03*
X495555Y369500D03*
X507355Y390800D03*
X497778Y843000D03*
Y838500D03*
Y847000D03*
X498500Y867500D03*
X505678Y995500D03*
X498178D03*
X525679Y136250D03*
X517679Y125750D03*
X513407Y311502D03*
X513500Y315800D03*
X522345Y311699D03*
X522365Y316365D03*
X521800Y322000D03*
X527667Y322182D03*
X523500Y347500D03*
Y352000D03*
Y342000D03*
X523100Y364300D03*
X526800Y359600D03*
X519500Y365500D03*
X523500Y357500D03*
X521500Y632500D03*
X521178Y995500D03*
X513678D03*
X538875Y138000D03*
X542000Y249000D03*
X528600Y316700D03*
X539300Y317600D03*
X534000Y317500D03*
X539200Y324100D03*
X530000Y342000D03*
X529400Y352800D03*
X530100Y347200D03*
X536678Y996000D03*
X530083Y995500D03*
X546500Y147500D03*
X547500Y360168D03*
X560678Y996000D03*
X577000Y58000D03*
X574000Y269000D03*
X563250Y262500D03*
X571555Y326000D03*
X562055Y347500D03*
X567500Y457500D03*
X563000Y453000D03*
X567500D03*
Y462000D03*
Y466500D03*
X563000Y457500D03*
Y462000D03*
Y466500D03*
X569178Y996000D03*
X576678D03*
X579221Y237250D03*
X580828Y260028D03*
X584678Y994500D03*
X604500Y205000D03*
Y200500D03*
X603500Y218500D03*
Y214000D03*
X594500Y236000D03*
X610500Y333000D03*
X606000Y341500D03*
X609000Y345500D03*
X598178Y983500D03*
X615000Y333000D03*
X620500D03*
X611500Y341500D03*
X613500Y345500D03*
X616500Y341500D03*
X621500D03*
X642000Y335000D03*
X639000Y332000D03*
X638500Y409000D03*
X634500Y427000D03*
X637000Y431500D03*
X632500D03*
X637000Y436500D03*
X632500D03*
X641625Y465375D03*
X628250Y570200D03*
X646500Y101000D03*
X650500D03*
X651500Y408500D03*
X646500D03*
X647125Y429375D03*
X656162Y472338D03*
X654500Y494000D03*
X647252Y576500D03*
X662248Y101000D03*
X670454Y94544D03*
X667748Y104000D03*
X670522Y130200D03*
X673500Y334000D03*
X668000D03*
X662000D03*
X663500Y452000D03*
X672500D03*
X660000Y443500D03*
X663500Y456000D03*
Y460500D03*
X667500Y454000D03*
Y458500D03*
X672500Y456000D03*
Y460500D03*
X690966Y142028D03*
X687055Y258500D03*
X683055D03*
X678055D03*
X681000Y452000D03*
X690500Y468000D03*
X681000Y456000D03*
Y460500D03*
X676500Y454000D03*
Y458500D03*
X690000Y460500D03*
X687968Y755284D03*
Y781784D03*
X700000Y60500D03*
X703053Y133568D03*
X704716Y156520D03*
X700216Y156368D03*
X706055Y258500D03*
X705500Y352500D03*
X707000Y340500D03*
X708500Y365000D03*
X707000Y385000D03*
Y378000D03*
X708500Y371000D03*
X694000Y483500D03*
X693500Y472000D03*
X694000Y492000D03*
Y500500D03*
Y507500D03*
Y514000D03*
X705900Y569200D03*
X698818Y759350D03*
X703328Y800144D03*
X697250Y876750D03*
X715716Y82652D03*
X713716Y121284D03*
X721716Y112784D03*
Y116784D03*
X717716Y121284D03*
X721716D03*
Y129284D03*
Y125284D03*
X722716Y156520D03*
X718216D03*
X713716D03*
X709216D03*
X721200Y205800D03*
X710055Y258500D03*
X714055D03*
X711500Y385000D03*
Y378000D03*
X720500Y478750D03*
X723168Y774984D03*
X712500Y859750D03*
X716250Y860250D03*
X723000Y996500D03*
X729716Y121284D03*
X725716D03*
X727248Y141500D03*
X727216Y156520D03*
X733498Y180750D03*
X733000Y193000D03*
X732500Y485500D03*
X734500Y547500D03*
X734462Y553538D03*
X733268Y757984D03*
X735000Y780500D03*
X727468Y819284D03*
X733440Y875560D03*
X731498Y996500D03*
X739368Y996610D03*
X727558Y996500D03*
X757200Y103100D03*
X746716Y130238D03*
X750916Y130272D03*
X745500Y145000D03*
X756000Y180000D03*
X749750Y454000D03*
X755300Y489300D03*
X746750Y571750D03*
X748000Y579500D03*
X745400Y877600D03*
X761000Y88500D03*
Y82500D03*
X760600Y94500D03*
X760522Y116784D03*
X770000Y123500D03*
X770500Y136000D03*
X770900Y144300D03*
X765116Y187659D03*
X771000Y464000D03*
X765009Y563491D03*
X760125Y666875D03*
X770646Y685354D03*
X777500Y351000D03*
X782500D03*
X788600Y449300D03*
X784800D03*
X776468Y447600D03*
X784900Y453000D03*
X788800D03*
X784274Y486274D03*
X790600Y547600D03*
X790000Y554500D03*
X785500Y666500D03*
X783746Y692754D03*
X787500Y783500D03*
X782750Y845750D03*
X781000Y877000D03*
X776750Y964750D03*
X806274Y434726D03*
X791000Y562000D03*
X802500Y579500D03*
X794000Y723500D03*
X791500Y783500D03*
X805250Y865750D03*
X794500Y897000D03*
X800500Y977500D03*
X794500D03*
X800500Y982000D03*
X794500D03*
X818500Y361600D03*
X813500Y367000D03*
X811000Y430500D03*
X810000Y735500D03*
X814000Y849500D03*
X810000Y980000D03*
X838055Y262500D03*
X828500Y361500D03*
X837000D03*
X825500Y411100D03*
X832500Y404000D03*
X826500Y436000D03*
X826000Y465078D03*
X831000Y598500D03*
X839250Y854500D03*
X826060Y863440D03*
X840000Y980000D03*
X847055Y262500D03*
X851555D03*
X854820Y352380D03*
X846500Y362000D03*
X842000Y367000D03*
Y372000D03*
Y377500D03*
X852000Y401500D03*
X842000D03*
X847000Y396500D03*
Y401500D03*
Y406500D03*
X854000Y436500D03*
X846250Y642250D03*
X854000Y640500D03*
X852500Y710500D03*
X842500Y719500D03*
X852600Y868500D03*
X872000Y75500D03*
X866112Y85626D03*
X865055Y262500D03*
X871500Y484000D03*
X871000Y639500D03*
X870500Y665060D03*
X861250Y649250D03*
X865500Y690500D03*
X860500Y734000D03*
X870000Y980000D03*
X888750Y324660D03*
X884120Y351630D03*
X877000Y409500D03*
X874450Y463500D03*
X877500Y612500D03*
X884200Y636500D03*
X878500Y695500D03*
X902000Y63000D03*
X904600Y406600D03*
X900000Y980000D03*
X935000Y51500D03*
X937000Y63000D03*
X930500Y219000D03*
X936500D03*
X930500Y232000D03*
X936500D03*
Y225500D03*
X930500D03*
X936000Y373500D03*
X934000Y448700D03*
X968085Y452065D03*
X980078Y204578D03*
X980960Y195257D03*
X989000Y66500D03*
X996500Y167000D03*
X988660Y190500D03*
X998000Y461500D03*
X1002500Y520000D03*
X994500Y543800D03*
X1001000Y771500D03*
X1007000Y12000D03*
X1012000Y43000D03*
X1017274Y219274D03*
X1013000Y282500D03*
X1012900Y275300D03*
X1007500Y487500D03*
X1016500Y519500D03*
X1008500Y543700D03*
X1007032Y879968D03*
X1010000Y980000D03*
X1032000Y82500D03*
Y90000D03*
Y97000D03*
Y103500D03*
Y110000D03*
X1036019Y203177D03*
X1036000Y199500D03*
X1035922Y209578D03*
X1031800Y248800D03*
X1027500Y248500D03*
X1036300Y248800D03*
X1052500Y187500D03*
X1042500Y930000D03*
X1040000Y980000D03*
X1060000Y207500D03*
X1060500Y282500D03*
X1060600Y303150D03*
X1056100Y303200D03*
X1059900Y295200D03*
X1059800Y290600D03*
X1061696Y761294D03*
X1061356Y753354D03*
X1071000Y71000D03*
X1077250Y102000D03*
X1077500Y97000D03*
Y107500D03*
X1086000Y126500D03*
Y187500D03*
X1080300Y191000D03*
X1084500Y202500D03*
X1086000Y192500D03*
X1074500Y627500D03*
X1073000Y637500D03*
X1071500Y739000D03*
X1077500Y759000D03*
X1085468Y895968D03*
X1070000Y980000D03*
X1088000Y85500D03*
X1098000Y126500D03*
X1102000Y250000D03*
X1102500Y264500D03*
X1089500Y405000D03*
X1088400Y647484D03*
X1098000Y775000D03*
X1093000Y791000D03*
X1097500Y784500D03*
X1098500Y823344D03*
X1092718Y859984D03*
X1093468Y896968D03*
X1100000Y980000D03*
X1113500Y614250D03*
X1113000Y630500D03*
X1105000D03*
X1110790Y738850D03*
X1107000Y757500D03*
X1114500Y855500D03*
X1119000D03*
X1118034Y847034D03*
X1113768D03*
X1116468Y870284D03*
Y874284D03*
Y865784D03*
X1112468Y870284D03*
X1114500Y886000D03*
X1103000Y888300D03*
X1118500Y886000D03*
X1123000Y250500D03*
X1120600Y282300D03*
X1126000Y618000D03*
X1122985Y670262D03*
X1122938Y676540D03*
X1119265Y683864D03*
X1135551Y685967D03*
X1135570Y711218D03*
X1132398Y720624D03*
X1132960Y752950D03*
X1126210Y752810D03*
X1134245Y769145D03*
X1127945Y769970D03*
X1121215Y769936D03*
X1135000Y810000D03*
X1134244Y799984D03*
X1121000Y808500D03*
X1127945Y799935D03*
X1121646Y799924D03*
X1121000Y823500D03*
X1123500Y832470D03*
X1135500Y835000D03*
X1135468Y854032D03*
X1120468Y870284D03*
X1131275Y867725D03*
X1130000Y980000D03*
X1145800Y282284D03*
X1151500Y449000D03*
X1147000Y619000D03*
X1151337Y660807D03*
X1141868Y680064D03*
X1151337Y670256D03*
X1151300Y682854D03*
Y692303D03*
Y689153D03*
Y686004D03*
Y695452D03*
X1148150D03*
Y692303D03*
Y689153D03*
Y686004D03*
Y682854D03*
X1151300Y698602D03*
X1148150D03*
X1145265Y776945D03*
X1151592Y773748D03*
X1140650Y782496D03*
X1151565Y787951D03*
X1142110Y792660D03*
X1149400Y800000D03*
X1142010Y809500D03*
X1137000Y890000D03*
X1144500D03*
X1152000D03*
X1162468Y257968D03*
X1168000Y302500D03*
X1166000Y290000D03*
X1168076Y310046D03*
X1152500Y311000D03*
X1158000Y309500D03*
X1152500Y318500D03*
X1160000D03*
X1167000Y321000D03*
Y326450D03*
X1155000Y594500D03*
X1165476Y613393D03*
X1152500Y608500D03*
X1165672Y609672D03*
X1159100Y640800D03*
X1154218Y679964D03*
X1154496Y667096D03*
X1160748Y682854D03*
X1157599Y686004D03*
X1154449D03*
Y682854D03*
Y689153D03*
X1160748Y695452D03*
X1157599D03*
Y692303D03*
X1154449Y695452D03*
Y692303D03*
X1163898Y695452D03*
X1160748Y692303D03*
X1163898D03*
X1157599Y689153D03*
X1160748D03*
X1163898D03*
X1160748Y686004D03*
X1163898D03*
Y698602D03*
X1160748D03*
X1157599D03*
X1154449D03*
X1166100Y731500D03*
X1152023Y733299D03*
X1160333Y753600D03*
X1167320Y770290D03*
X1157871Y773728D03*
X1167330Y795830D03*
X1163605Y783513D03*
X1167277Y792658D03*
X1157866Y795844D03*
X1165300Y809610D03*
X1160300D03*
X1154300D03*
X1155390Y818000D03*
X1157990Y827000D03*
X1158000Y890000D03*
X1164500D03*
X1155000Y980000D03*
X1177500Y290000D03*
X1174752Y320504D03*
X1175000Y327000D03*
X1176500Y383500D03*
X1182500Y407000D03*
X1179934Y567000D03*
X1176496Y698564D03*
X1179671Y698565D03*
X1184750Y781000D03*
X1170300Y809610D03*
X1196334Y290561D03*
X1185283Y290513D03*
X1198000Y348000D03*
X1192000Y344500D03*
X1197000Y372500D03*
X1187500Y411000D03*
X1197000Y409500D03*
X1185945Y695415D03*
X1196000Y710500D03*
X1188000Y762500D03*
X1198718Y800782D03*
X1188875Y856625D03*
X1185000Y980000D03*
X1203500Y193800D03*
Y198000D03*
X1208000D03*
Y193800D03*
X1201922Y248500D03*
X1202177Y260000D03*
X1208500Y283500D03*
X1208000Y271499D03*
Y297638D03*
Y309000D03*
X1206500Y330000D03*
X1208500Y321500D03*
X1203500Y345000D03*
X1208500Y346400D03*
Y359000D03*
X1208000Y371000D03*
X1209000Y438500D03*
X1209500Y561910D03*
X1215500Y605300D03*
X1203500Y698520D03*
X1210500Y733500D03*
X1201968Y757500D03*
X1212840Y781000D03*
X1204000Y862000D03*
X1217250Y862250D03*
X1211500Y882500D03*
X1215000Y980000D03*
X1225500Y714500D03*
X1230500Y841000D03*
X1239500Y204000D03*
Y214000D03*
X1239000Y251500D03*
X1241777Y265700D03*
X1241377Y274900D03*
X1238500Y290000D03*
X1239000Y302437D03*
X1238500Y316500D03*
X1250158Y326463D03*
X1238500Y325985D03*
X1239000Y338900D03*
Y352800D03*
X1239500Y366000D03*
X1234177Y379500D03*
X1243000Y446650D03*
X1249000Y723250D03*
X1248500Y775500D03*
X1248950Y782450D03*
X1245650Y821850D03*
X1245000Y980000D03*
X1256500Y166500D03*
X1261000D03*
X1265000Y169000D03*
Y174000D03*
X1258000Y205000D03*
X1265000Y211500D03*
X1261000Y207500D03*
Y211500D03*
X1251500Y266500D03*
X1251700Y274000D03*
X1254203Y282770D03*
X1261000Y292500D03*
X1261006Y303543D03*
X1252564Y290566D03*
X1253500Y316500D03*
Y305000D03*
X1257000Y311000D03*
X1258562Y672438D03*
X1259000Y699500D03*
X1257500Y710500D03*
X1259500Y724000D03*
X1264000Y853000D03*
X1281000Y475000D03*
X1276500D03*
X1271000Y573500D03*
Y568500D03*
X1282500Y598000D03*
Y645000D03*
X1282300Y678000D03*
X1276000Y694000D03*
X1272700Y694900D03*
X1277000Y712500D03*
X1272500D03*
X1275000Y732000D03*
X1277500Y757500D03*
Y778500D03*
X1267500Y779000D03*
X1275000Y980000D03*
X1290874Y34376D03*
X1295500Y291500D03*
X1285500Y475000D03*
X1293500D03*
X1297500Y562000D03*
X1286500Y569000D03*
X1291500Y666000D03*
X1298034Y907034D03*
X1309500Y51000D03*
X1311000Y435000D03*
X1307900Y577412D03*
X1306617Y587512D03*
X1308817Y595412D03*
X1311000Y651900D03*
X1306000Y782500D03*
X1314284D03*
X1304500Y838000D03*
X1300784Y838716D03*
X1303750Y862250D03*
X1307468Y884532D03*
X1300000Y980000D03*
X1331000Y120000D03*
X1322000Y318500D03*
X1324500Y345400D03*
Y341000D03*
X1329000Y341100D03*
Y345500D03*
X1323000Y368000D03*
X1327500D03*
X1332000D03*
Y372400D03*
X1327500D03*
X1323000D03*
X1319400Y522100D03*
X1318700Y533500D03*
X1323117Y626412D03*
X1329468Y666468D03*
X1318784Y793716D03*
X1321466Y907034D03*
X1330000Y980000D03*
X1347000Y88000D03*
X1347500Y116000D03*
X1338000Y341100D03*
X1333500D03*
Y345500D03*
X1338000D03*
X1334500Y557000D03*
X1344617Y588712D03*
Y593412D03*
X1346617Y626912D03*
X1342367Y627662D03*
X1333468Y680000D03*
X1354500Y276000D03*
X1358500Y288916D03*
X1354900Y522600D03*
X1355900Y536600D03*
X1355500Y556500D03*
X1360817Y557812D03*
X1349317Y593412D03*
X1353117Y610412D03*
X1363100Y627000D03*
X1349817Y628612D03*
X1360000Y980000D03*
X1369720Y106365D03*
X1375500Y328000D03*
X1378500Y370000D03*
Y365000D03*
Y360000D03*
X1377000Y384000D03*
Y379000D03*
X1378500Y374500D03*
X1377000Y390000D03*
X1374500Y395000D03*
Y402000D03*
X1372500Y415000D03*
X1368000Y450500D03*
X1369617Y557012D03*
X1378800Y594900D03*
X1390004Y106000D03*
G54D45*
X1338526Y29526D03*
G54D32*
X545079Y315945D03*
X556889Y298230D03*
X552954Y290355D03*
X560829Y315945D03*
X572639Y298230D03*
X568699Y290355D03*
X576574Y315945D03*
X564764Y308070D03*
X588384Y298230D03*
X584449Y290355D03*
X592324Y315945D03*
X580514Y308070D03*
X604134Y298230D03*
X600199Y290355D03*
X608069Y315945D03*
X596259Y308070D03*
X619884Y298230D03*
X615944Y290355D03*
X627754Y308070D03*
X623819Y315945D03*
X612009Y308070D03*
X635629Y298230D03*
X631694Y290355D03*
X643504Y308070D03*
X639569Y315945D03*
X651379Y298230D03*
X647439Y290355D03*
X659254Y308070D03*
X655314Y315945D03*
X667124Y298230D03*
X663189Y290355D03*
X674999Y308070D03*
X671064Y315945D03*
X682874Y298230D03*
X678939Y290355D03*
X690749Y308070D03*
X686809Y315945D03*
X698624Y298230D03*
X694684Y290355D03*
X706494Y308070D03*
X702559Y315945D03*
X726179Y290355D03*
X714369Y298230D03*
X710434Y290355D03*
X722244Y308070D03*
X718309Y315945D03*
X741929Y290355D03*
X730119Y298230D03*
X737994Y308070D03*
X734054Y315945D03*
X757679Y290355D03*
X745864Y298230D03*
X753739Y308070D03*
X749804Y315945D03*
X773424Y290355D03*
X761614Y298230D03*
X769489Y308070D03*
X765549Y315945D03*
X789174Y290355D03*
X777364Y298230D03*
X785234Y308070D03*
X781299Y315945D03*
X804919Y290355D03*
X793109Y298230D03*
X800984Y308070D03*
X797049Y315945D03*
X820669Y290355D03*
X808859Y298230D03*
X816734Y308070D03*
X812794Y315945D03*
X848229Y308070D03*
X860039Y290355D03*
Y315945D03*
G54D23*
X200000Y391500D03*
X216500D03*
G54D46*
X1367067Y60039D03*
Y96260D03*
X1392657Y60039D03*
Y96260D03*
G54D30*
X537994Y303150D03*
X825984D03*
G54D37*
X1008268Y244094D03*
Y411417D03*
X1227166Y155511D03*
X1227165Y411417D03*
G54D14*
X15000Y1008622D03*
X90119Y72219D03*
X227041Y1008622D03*
X653974Y1008621D03*
X955315Y850829D03*
X1157095Y128841D03*
X1385000Y1008622D03*
X1387875Y-15015D03*
G54D26*
X270078Y92125D03*
Y155117D03*
X490944Y79921D03*
Y255118D03*
X743897Y353543D03*
Y410629D03*
X1305117Y87548D03*
Y262745D03*
X1376968Y147243D03*
Y216535D03*
G54D38*
X1045000Y32598D03*
X1096732D03*
G54D35*
X600925Y44134D03*
X638917D03*
G54D27*
X332086Y408858D03*
X355708Y96456D03*
X450196Y257874D03*
X572243Y337992D03*
G54D16*
X25000Y980000D03*
X45000D03*
X55000Y975000D03*
X65000Y980000D03*
X75000Y975000D03*
X95000D03*
X206000Y982000D03*
X226000D03*
X246000D03*
X324500Y6000D03*
Y10500D03*
X1105000Y15000D03*
Y75000D03*
Y105000D03*
Y135000D03*
X1211500Y5500D03*
Y35500D03*
Y65500D03*
Y85500D03*
Y107500D03*
Y137500D03*
G54D20*
X147500Y472100D03*
X140000Y720000D03*
Y740000D03*
X182800Y471300D03*
X180000Y760000D03*
X220000D03*
X260000Y260000D03*
Y760000D03*
X378500Y812000D03*
Y824500D03*
X406500Y713500D03*
X412000Y724000D03*
X409500Y775500D03*
X422500Y764500D03*
X440000Y5000D03*
X431000Y713500D03*
Y724000D03*
X460000Y5000D03*
X477500Y715000D03*
X485000Y5000D03*
X491500Y715000D03*
X490500Y800000D03*
X504500Y715000D03*
X502500Y800000D03*
X515000Y5000D03*
X545000D03*
X560000Y20000D03*
X575000Y5000D03*
X604500Y714500D03*
X606000Y918500D03*
X616500Y714500D03*
X613500Y744500D03*
Y759000D03*
X620500Y848500D03*
X634000Y734500D03*
X633500Y749500D03*
X630500Y912000D03*
X650000Y110000D03*
X657500Y827000D03*
X656500Y906000D03*
X660000Y120000D03*
X685000Y5000D03*
X682500Y917500D03*
X695000Y20000D03*
X715000Y5000D03*
X725000Y20000D03*
X720000Y905000D03*
X728966Y53966D03*
Y65466D03*
X745000Y5000D03*
X755000Y20000D03*
X747800Y50200D03*
X762250Y71000D03*
X775000Y5000D03*
X785000Y20000D03*
X805000Y5000D03*
X800000Y100000D03*
X815000Y20000D03*
X810000Y120000D03*
X820500Y754000D03*
Y765500D03*
X835000Y5000D03*
X850000Y20000D03*
X865000Y5000D03*
X870000Y160000D03*
X880000Y20000D03*
X895000Y5000D03*
X890000Y140000D03*
X910000Y20000D03*
Y160000D03*
X915000Y805000D03*
Y825000D03*
Y845000D03*
Y865000D03*
Y885000D03*
Y905000D03*
Y925000D03*
Y945000D03*
Y965000D03*
X925000Y5000D03*
X955000D03*
X940000Y20000D03*
X970000D03*
X965000Y725500D03*
X985000Y5000D03*
X980000Y725500D03*
X1000000Y20000D03*
X1000500Y667500D03*
X990000D03*
X1015000Y5000D03*
X1045000D03*
X1060000Y20000D03*
X1075000Y5000D03*
X1090000Y20000D03*
X1100000Y180000D03*
X1091500Y846500D03*
X1105000Y5000D03*
Y400500D03*
X1235500Y5000D03*
X1268000D03*
X1307500D03*
X1305217Y612412D03*
X1305435Y603918D03*
X1337500Y5000D03*
X1354500Y703500D03*
X1379600Y584200D03*
X1377800Y603800D03*
X1378082Y614266D03*
X1381637Y611225D03*
X1381578Y607117D03*
X1394122Y5878D03*
X1387200Y584100D03*
X1384400Y598300D03*
Y601900D03*
G54D21*
X153937Y238898D03*
Y246772D03*
Y260551D03*
X224015Y234961D03*
Y246772D03*
Y260551D03*
G54D34*
X585315Y44134D03*
X654527D03*
G54D25*
X200118Y739409D03*
X190118D03*
X210118D03*
X230118Y729409D03*
Y739409D03*
X220118D03*
X250118D03*
X240118D03*
X260118Y729409D03*
Y739409D03*
X270118Y729409D03*
Y739409D03*
G54D11*
X19272Y337795D03*
Y396850D03*
X98838Y337795D03*
Y396850D03*
G54D40*
X1084646Y43267D03*
%LPC*%
G75*
G54D48*
G01X-245081Y-422119D02*
G02I-12000J0D01*
G01X-250231D02*
G02I-6850J0D01*
G01X-241081D02*
X-273081D01*
G01X-257081Y-438119D02*
Y-406119D01*
G01X-241081Y-438119D02*
Y-518119D01*
G01D02*
X1034819D01*
G01X-241081Y-473619D02*
X1034819D01*
G01X-241081Y-438119D02*
X1034819D01*
G01X247319D02*
Y-518119D01*
G01X384819Y-438119D02*
Y-518119D01*
G01X499819Y-438119D02*
Y-518119D01*
G01X667319Y-438119D02*
Y-518119D01*
G01X837319Y-438119D02*
Y-518119D01*
G01X1034819Y-438119D02*
Y-518119D01*
G01X1066819Y-422119D02*
X1034819D01*
G01X1050819Y-438119D02*
Y-406119D01*
G01X1062819Y-422119D02*
G02I-12000J0D01*
G01X1057669D02*
G02I-6850J0D01*
G54D49*
G01X-185516Y-508119D02*
Y-490619D01*
G01X-176346D02*
Y-508119D01*
G01Y-499369D02*
X-185516D01*
G01X-163431Y-508119D02*
X-165178Y-507827D01*
X-166706Y-506661D01*
X-168016Y-504911D01*
X-168890Y-502869D01*
X-169326Y-500536D01*
Y-498202D01*
X-168890Y-495869D01*
X-168016Y-493827D01*
X-166706Y-492078D01*
X-165178Y-490911D01*
X-163431Y-490619D01*
X-161685Y-490911D01*
X-160156Y-492078D01*
X-158846Y-493827D01*
X-157972Y-495869D01*
X-157536Y-498202D01*
Y-500536D01*
X-157972Y-502869D01*
X-158846Y-504911D01*
X-160156Y-506661D01*
X-161685Y-507827D01*
X-163431Y-508119D01*
G01X-150953D02*
Y-490619D01*
X-140909Y-508119D01*
Y-490619D01*
G01X-124064Y-508119D02*
X-132798D01*
Y-490619D01*
X-124064D01*
G01X-127558Y-499077D02*
X-132798D01*
G01X-110931Y-508119D02*
Y-500244D01*
X-115298Y-490619D01*
G01X-106564D02*
X-110931Y-500244D01*
G01X-74185Y-498786D02*
X-73311Y-497911D01*
X-72656Y-496453D01*
X-72219Y-494410D01*
X-72656Y-492661D01*
X-73529Y-491494D01*
X-75058Y-490619D01*
X-80953D01*
Y-508119D01*
X-73748D01*
X-72219Y-506953D01*
X-71346Y-505202D01*
X-70909Y-503161D01*
X-71346Y-501119D01*
X-72656Y-499369D01*
X-74185Y-498786D01*
X-80953D01*
G01X-63890Y-508119D02*
X-58431Y-490619D01*
X-52972Y-508119D01*
G01X-54938Y-501994D02*
X-61925D01*
G01X-45734Y-508119D02*
Y-490619D01*
X-41368D01*
X-39621Y-491494D01*
X-38311Y-492661D01*
X-37219Y-494410D01*
X-36346Y-496453D01*
X-36128Y-499369D01*
X-36346Y-502286D01*
X-37219Y-504328D01*
X-38311Y-506078D01*
X-39621Y-507244D01*
X-41368Y-508119D01*
X-45734D01*
G01X-22121Y-499369D02*
X-17754D01*
Y-504619D01*
X-19064Y-506369D01*
X-20593Y-507536D01*
X-22776Y-508119D01*
X-24959Y-507536D01*
X-26488Y-506369D01*
X-27798Y-504619D01*
X-28671Y-502577D01*
X-29108Y-500244D01*
Y-498202D01*
X-28671Y-496453D01*
X-27798Y-494410D01*
X-26488Y-492661D01*
X-25178Y-491494D01*
X-23431Y-490619D01*
X-21903D01*
X-20156Y-491202D01*
X-18846Y-492369D01*
G01X-1564Y-508119D02*
X-10298D01*
Y-490619D01*
X-1564D01*
G01X-5058Y-499077D02*
X-10298D01*
G01X7202Y-508119D02*
Y-490619D01*
X12661D01*
X14407Y-491494D01*
X15499Y-492661D01*
X15936Y-494994D01*
X15499Y-497328D01*
X14189Y-498786D01*
X12661Y-499661D01*
X7202D01*
G01X12661D02*
X15936Y-508119D01*
G01X48315Y-498786D02*
X49189Y-497911D01*
X49844Y-496453D01*
X50281Y-494410D01*
X49844Y-492661D01*
X48971Y-491494D01*
X47442Y-490619D01*
X41547D01*
Y-508119D01*
X48752D01*
X50281Y-506953D01*
X51154Y-505202D01*
X51591Y-503161D01*
X51154Y-501119D01*
X49844Y-499369D01*
X48315Y-498786D01*
X41547D01*
G01X58610Y-508119D02*
X64069Y-490619D01*
X69528Y-508119D01*
G01X67562Y-501994D02*
X60575D01*
G01X76984Y-505786D02*
X78731Y-507244D01*
X80696Y-508119D01*
X82442D01*
X84189Y-507244D01*
X85499Y-505786D01*
X86154Y-503744D01*
X85717Y-501703D01*
X84626Y-499952D01*
X82661Y-498786D01*
X80041Y-498202D01*
X78512Y-497036D01*
X77857Y-494994D01*
X78294Y-492952D01*
X79386Y-491494D01*
X80914Y-490619D01*
X82442D01*
X83971Y-491202D01*
X85281Y-492661D01*
G01X103436Y-508119D02*
X94702D01*
Y-490619D01*
X103436D01*
G01X99942Y-499077D02*
X94702D01*
G01X118315Y-498786D02*
X119189Y-497911D01*
X119844Y-496453D01*
X120281Y-494410D01*
X119844Y-492661D01*
X118971Y-491494D01*
X117442Y-490619D01*
X111547D01*
Y-508119D01*
X118752D01*
X120281Y-506953D01*
X121154Y-505202D01*
X121591Y-503161D01*
X121154Y-501119D01*
X119844Y-499369D01*
X118315Y-498786D01*
X111547D01*
G01X134069Y-508119D02*
X132322Y-507827D01*
X130794Y-506661D01*
X129484Y-504911D01*
X128610Y-502869D01*
X128174Y-500536D01*
Y-498202D01*
X128610Y-495869D01*
X129484Y-493827D01*
X130794Y-492078D01*
X132322Y-490911D01*
X134069Y-490619D01*
X135815Y-490911D01*
X137344Y-492078D01*
X138654Y-493827D01*
X139528Y-495869D01*
X139964Y-498202D01*
Y-500536D01*
X139528Y-502869D01*
X138654Y-504911D01*
X137344Y-506661D01*
X135815Y-507827D01*
X134069Y-508119D01*
G01X146110D02*
X151569Y-490619D01*
X157028Y-508119D01*
G01X155062Y-501994D02*
X148075D01*
G01X164702Y-508119D02*
Y-490619D01*
X170161D01*
X171907Y-491494D01*
X172999Y-492661D01*
X173436Y-494994D01*
X172999Y-497328D01*
X171689Y-498786D01*
X170161Y-499661D01*
X164702D01*
G01X170161D02*
X173436Y-508119D01*
G01X181766D02*
Y-490619D01*
X186132D01*
X187879Y-491494D01*
X189189Y-492661D01*
X190281Y-494410D01*
X191154Y-496453D01*
X191372Y-499369D01*
X191154Y-502286D01*
X190281Y-504328D01*
X189189Y-506078D01*
X187879Y-507244D01*
X186132Y-508119D01*
X181766D01*
G01X-37858Y-463119D02*
Y-445619D01*
X-32181Y-460202D01*
X-26504Y-445619D01*
Y-463119D01*
G01X-14681D02*
X-15991Y-462827D01*
X-17301Y-461661D01*
X-18175Y-459619D01*
X-18611Y-457286D01*
X-18175Y-454952D01*
X-17301Y-452911D01*
X-15991Y-451744D01*
X-14681Y-451453D01*
X-13371Y-451744D01*
X-12061Y-452911D01*
X-11188Y-454952D01*
X-10969Y-457286D01*
X-11188Y-459619D01*
X-12061Y-461661D01*
X-13371Y-462827D01*
X-14681Y-463119D01*
G01X6749Y-445619D02*
Y-463119D01*
G01Y-460495D02*
X5876Y-461953D01*
X4565Y-462827D01*
X3037Y-463119D01*
X1291Y-462536D01*
X-19Y-461078D01*
X-893Y-459328D01*
X-1111Y-457286D01*
X-893Y-455244D01*
X-19Y-453494D01*
X1291Y-452036D01*
X3037Y-451453D01*
X4565Y-451744D01*
X5657Y-452328D01*
X6749Y-453494D01*
G01X17044Y-455244D02*
X24031D01*
X23376Y-453202D01*
X22284Y-452036D01*
X20756Y-451453D01*
X19227Y-451744D01*
X17917Y-452619D01*
X17044Y-454661D01*
X16607Y-456411D01*
Y-458161D01*
X17044Y-459911D01*
X18136Y-461661D01*
X19446Y-462827D01*
X20974Y-463119D01*
X22502Y-462536D01*
X24031Y-460786D01*
G01X37819Y-463119D02*
Y-445619D01*
G01X281019Y-508119D02*
Y-490619D01*
X278399Y-494119D01*
G01Y-508119D02*
X283639D01*
G01X293716Y-504619D02*
X295025Y-506661D01*
X296772Y-507827D01*
X298737Y-508119D01*
X300484Y-507827D01*
X302231Y-506369D01*
X303322Y-504619D01*
X303541Y-502869D01*
X303104Y-500828D01*
X301576Y-499369D01*
X300047Y-498786D01*
X298082D01*
G01X300047D02*
X301357Y-497911D01*
X302449Y-496453D01*
X302886Y-494703D01*
X302449Y-492952D01*
X301357Y-491494D01*
X299392Y-490619D01*
X297427Y-490911D01*
X295462Y-492078D01*
G01X312307Y-506078D02*
X313836Y-507536D01*
X315582Y-508119D01*
X317329Y-507536D01*
X318857Y-505786D01*
X319949Y-503161D01*
X320386Y-500536D01*
Y-497328D01*
X319949Y-494703D01*
X318857Y-492369D01*
X317547Y-491202D01*
X316019Y-490619D01*
X314272Y-491202D01*
X312962Y-492369D01*
X312089Y-494119D01*
X311652Y-496453D01*
X312089Y-498494D01*
X313181Y-500536D01*
X314491Y-501703D01*
X316019Y-501994D01*
X317765Y-501411D01*
X319076Y-499952D01*
X320386Y-497328D01*
G01X336139Y-508119D02*
Y-490619D01*
X328060Y-503161D01*
X338978D01*
G01X351019Y-508119D02*
X352547Y-507827D01*
X354294Y-506953D01*
X355386Y-505495D01*
X355822Y-503452D01*
X355386Y-501411D01*
X354076Y-499661D01*
X352111Y-498786D01*
X349927D01*
X348617Y-498202D01*
X347525Y-496744D01*
X347089Y-494703D01*
X347744Y-492661D01*
X349272Y-491202D01*
X351019Y-490619D01*
X352765Y-491202D01*
X354294Y-492661D01*
X354949Y-494703D01*
X354512Y-496744D01*
X353421Y-498202D01*
X352111Y-498786D01*
X349927D01*
X347962Y-499661D01*
X346652Y-501411D01*
X346216Y-503452D01*
X346652Y-505495D01*
X347744Y-506953D01*
X349491Y-507827D01*
X351019Y-508119D01*
G01X267902Y-463119D02*
Y-445619D01*
X273142D01*
X274889Y-446494D01*
X276199Y-448536D01*
X276636Y-450869D01*
X276199Y-453202D01*
X275107Y-454952D01*
X273142Y-455828D01*
X267902D01*
G01X294572Y-447078D02*
X293262Y-446202D01*
X291734Y-445619D01*
X289987D01*
X288022Y-446494D01*
X286494Y-447952D01*
X285402Y-449703D01*
X284529Y-452619D01*
X284310Y-455244D01*
X284747Y-457869D01*
X285402Y-459619D01*
X286712Y-461369D01*
X288241Y-462536D01*
X289769Y-463119D01*
X291297D01*
X292826Y-462536D01*
X294136Y-461661D01*
X295228Y-460495D01*
G01X309015Y-453786D02*
X309889Y-452911D01*
X310544Y-451453D01*
X310981Y-449410D01*
X310544Y-447661D01*
X309671Y-446494D01*
X308142Y-445619D01*
X302247D01*
Y-463119D01*
X309452D01*
X310981Y-461953D01*
X311854Y-460202D01*
X312291Y-458161D01*
X311854Y-456119D01*
X310544Y-454369D01*
X309015Y-453786D01*
X302247D01*
G01X318219Y-468952D02*
X331319D01*
G01X337247Y-463119D02*
Y-445619D01*
X347291Y-463119D01*
Y-445619D01*
G01X359769Y-463119D02*
X358022Y-462827D01*
X356494Y-461661D01*
X355184Y-459911D01*
X354310Y-457869D01*
X353874Y-455536D01*
Y-453202D01*
X354310Y-450869D01*
X355184Y-448827D01*
X356494Y-447078D01*
X358022Y-445911D01*
X359769Y-445619D01*
X361515Y-445911D01*
X363044Y-447078D01*
X364354Y-448827D01*
X365228Y-450869D01*
X365664Y-453202D01*
Y-455536D01*
X365228Y-457869D01*
X364354Y-459911D01*
X363044Y-461661D01*
X361515Y-462827D01*
X359769Y-463119D01*
G01X410610Y-445619D02*
X416069Y-463119D01*
X421528Y-445619D01*
G01X437936Y-463119D02*
X429202D01*
Y-445619D01*
X437936D01*
G01X434442Y-454077D02*
X429202D01*
G01X446702Y-463119D02*
Y-445619D01*
X452161D01*
X453907Y-446494D01*
X454999Y-447661D01*
X455436Y-449994D01*
X454999Y-452328D01*
X453689Y-453786D01*
X452161Y-454661D01*
X446702D01*
G01X452161D02*
X455436Y-463119D01*
G01X468569Y-463702D02*
X468132Y-463411D01*
Y-462827D01*
X468569Y-462536D01*
X469006Y-462827D01*
Y-463411D01*
X468569Y-463702D01*
G01X433569Y-508119D02*
Y-490619D01*
X430949Y-494119D01*
G01Y-508119D02*
X436189D01*
G01X452815Y-498786D02*
X453689Y-497911D01*
X454344Y-496453D01*
X454781Y-494410D01*
X454344Y-492661D01*
X453471Y-491494D01*
X451942Y-490619D01*
X446047D01*
Y-508119D01*
X453252D01*
X454781Y-506953D01*
X455654Y-505202D01*
X456091Y-503161D01*
X455654Y-501119D01*
X454344Y-499369D01*
X452815Y-498786D01*
X446047D01*
G01X622886Y-490619D02*
Y-508119D01*
X614152D01*
G01X605822Y-505495D02*
X604513Y-506953D01*
X602984Y-507827D01*
X601019Y-508119D01*
X599054Y-507536D01*
X597526Y-506369D01*
X596434Y-504328D01*
X596216Y-501994D01*
X596652Y-499661D01*
X597744Y-498202D01*
X599273Y-497036D01*
X600801Y-496744D01*
X602329Y-497036D01*
X604294Y-498202D01*
X603639Y-490619D01*
X597744D01*
G01X588978D02*
X583519Y-508119D01*
X578060Y-490619D01*
G01X561216Y-492078D02*
X562526Y-491202D01*
X564054Y-490619D01*
X565801D01*
X567766Y-491494D01*
X569294Y-492952D01*
X570386Y-494703D01*
X571259Y-497619D01*
X571478Y-500244D01*
X571041Y-502869D01*
X570386Y-504619D01*
X569076Y-506369D01*
X567547Y-507536D01*
X566019Y-508119D01*
X564491D01*
X562962Y-507536D01*
X561652Y-506661D01*
X560560Y-505495D01*
G01X543716Y-492078D02*
X545026Y-491202D01*
X546554Y-490619D01*
X548301D01*
X550266Y-491494D01*
X551794Y-492952D01*
X552886Y-494703D01*
X553759Y-497619D01*
X553978Y-500244D01*
X553541Y-502869D01*
X552886Y-504619D01*
X551576Y-506369D01*
X550047Y-507536D01*
X548519Y-508119D01*
X546991D01*
X545462Y-507536D01*
X544152Y-506661D01*
X543060Y-505495D01*
G01X544152Y-445619D02*
Y-463119D01*
X552886D01*
G01X569949D02*
Y-451453D01*
G01Y-453494D02*
X569076Y-452328D01*
X567765Y-451744D01*
X566237Y-451453D01*
X564709Y-452036D01*
X563399Y-453202D01*
X562525Y-454952D01*
X562089Y-457286D01*
X562525Y-459619D01*
X563399Y-461369D01*
X564709Y-462536D01*
X566237Y-463119D01*
X567765Y-462827D01*
X569076Y-461953D01*
X569949Y-460786D01*
G01X578934Y-468369D02*
X580244Y-468952D01*
X581991Y-468369D01*
X583082Y-467203D01*
X583956Y-465744D01*
X585265Y-461078D01*
X588104Y-451453D01*
G01X581117D02*
X585265Y-461078D01*
G01X597744Y-455244D02*
X604731D01*
X604076Y-453202D01*
X602984Y-452036D01*
X601456Y-451453D01*
X599927Y-451744D01*
X598617Y-452619D01*
X597744Y-454661D01*
X597307Y-456411D01*
Y-458161D01*
X597744Y-459911D01*
X598836Y-461661D01*
X600146Y-462827D01*
X601674Y-463119D01*
X603202Y-462536D01*
X604731Y-460786D01*
G01X615462Y-463119D02*
Y-451453D01*
G01Y-453786D02*
X616554Y-452619D01*
X617646Y-451744D01*
X619174Y-451453D01*
X620265Y-451744D01*
X621576Y-452619D01*
G01X686702Y-490619D02*
Y-508119D01*
X695436D01*
G01X703984Y-513369D02*
X705294Y-513952D01*
X707041Y-513369D01*
X708132Y-512203D01*
X709006Y-510744D01*
X710315Y-506078D01*
X713154Y-496453D01*
G01X706167D02*
X710315Y-506078D01*
G01X722357Y-508119D02*
Y-496453D01*
G01Y-499369D02*
X723231Y-497911D01*
X724541Y-496744D01*
X726287Y-496453D01*
X727815Y-496744D01*
X729126Y-497911D01*
X729781Y-499952D01*
Y-508119D01*
G01X739857D02*
Y-496453D01*
G01Y-499369D02*
X740731Y-497911D01*
X742041Y-496744D01*
X743787Y-496453D01*
X745315Y-496744D01*
X746626Y-497911D01*
X747281Y-499952D01*
Y-508119D01*
G01X774202Y-490619D02*
Y-508119D01*
X782936D01*
G01X796069Y-496453D02*
Y-508119D01*
G01Y-491786D02*
X795632Y-491494D01*
Y-490911D01*
X796069Y-490619D01*
X796506Y-490911D01*
Y-491494D01*
X796069Y-491786D01*
G01X809857Y-496453D02*
Y-504619D01*
X810731Y-506661D01*
X812041Y-507827D01*
X813569Y-508119D01*
X815097Y-507827D01*
X816407Y-506661D01*
X817281Y-504619D01*
G01Y-508119D02*
Y-496453D01*
G01X686266Y-463119D02*
Y-445619D01*
X690632D01*
X692379Y-446494D01*
X693689Y-447661D01*
X694781Y-449410D01*
X695654Y-451453D01*
X695872Y-454369D01*
X695654Y-457286D01*
X694781Y-459328D01*
X693689Y-461078D01*
X692379Y-462244D01*
X690632Y-463119D01*
X686266D01*
G01X705294Y-455244D02*
X712281D01*
X711626Y-453202D01*
X710534Y-452036D01*
X709006Y-451453D01*
X707477Y-451744D01*
X706167Y-452619D01*
X705294Y-454661D01*
X704857Y-456411D01*
Y-458161D01*
X705294Y-459911D01*
X706386Y-461661D01*
X707696Y-462827D01*
X709224Y-463119D01*
X710752Y-462536D01*
X712281Y-460786D01*
G01X722794Y-461078D02*
X723886Y-462244D01*
X725414Y-463119D01*
X726724D01*
X728034Y-462536D01*
X728907Y-461661D01*
X729344Y-460495D01*
X729126Y-458744D01*
X728252Y-457869D01*
X724322Y-456119D01*
X723449Y-454077D01*
X723886Y-452619D01*
X724759Y-451744D01*
X726069Y-451453D01*
X727379Y-451744D01*
X728689Y-452619D01*
G01X743569Y-451453D02*
Y-463119D01*
G01Y-446786D02*
X743132Y-446494D01*
Y-445911D01*
X743569Y-445619D01*
X744006Y-445911D01*
Y-446494D01*
X743569Y-446786D01*
G01X758012Y-467494D02*
X759541Y-468661D01*
X761287Y-468952D01*
X762815Y-468661D01*
X764126Y-467203D01*
X764999Y-465161D01*
Y-451453D01*
G01Y-453786D02*
X764126Y-452619D01*
X762815Y-451744D01*
X761287Y-451453D01*
X759541Y-452036D01*
X758449Y-453202D01*
X757575Y-455244D01*
X757139Y-457286D01*
X757357Y-459036D01*
X758231Y-461078D01*
X759541Y-462536D01*
X761287Y-463119D01*
X762597Y-462827D01*
X764126Y-461661D01*
X764999Y-460495D01*
G01X774857Y-463119D02*
Y-451453D01*
G01Y-454369D02*
X775731Y-452911D01*
X777041Y-451744D01*
X778787Y-451453D01*
X780315Y-451744D01*
X781626Y-452911D01*
X782281Y-454952D01*
Y-463119D01*
G01X792794Y-455244D02*
X799781D01*
X799126Y-453202D01*
X798034Y-452036D01*
X796506Y-451453D01*
X794977Y-451744D01*
X793667Y-452619D01*
X792794Y-454661D01*
X792357Y-456411D01*
Y-458161D01*
X792794Y-459911D01*
X793886Y-461661D01*
X795196Y-462827D01*
X796724Y-463119D01*
X798252Y-462536D01*
X799781Y-460786D01*
G01X810512Y-463119D02*
Y-451453D01*
G01Y-453786D02*
X811604Y-452619D01*
X812696Y-451744D01*
X814224Y-451453D01*
X815315Y-451744D01*
X816626Y-452619D01*
G01X857269Y-508119D02*
Y-490619D01*
X854649Y-494119D01*
G01Y-508119D02*
X859889D01*
G01X874769D02*
Y-490619D01*
X872149Y-494119D01*
G01Y-508119D02*
X877389D01*
G01X888339Y-508702D02*
X896199Y-490619D01*
G01X909769Y-508119D02*
Y-490619D01*
X907149Y-494119D01*
G01Y-508119D02*
X912389D01*
G01X922466Y-504619D02*
X923775Y-506661D01*
X925522Y-507827D01*
X927487Y-508119D01*
X929234Y-507827D01*
X930981Y-506369D01*
X932072Y-504619D01*
X932291Y-502869D01*
X931854Y-500828D01*
X930326Y-499369D01*
X928797Y-498786D01*
X926832D01*
G01X928797D02*
X930107Y-497911D01*
X931199Y-496453D01*
X931636Y-494703D01*
X931199Y-492952D01*
X930107Y-491494D01*
X928142Y-490619D01*
X926177Y-490911D01*
X924212Y-492078D01*
G01X940839Y-508702D02*
X948699Y-490619D01*
G01X958121Y-493536D02*
X959431Y-491786D01*
X960959Y-490911D01*
X962706Y-490619D01*
X964889Y-491202D01*
X966417Y-492661D01*
X966854Y-494410D01*
X966636Y-496161D01*
X965762Y-497619D01*
X961396Y-500536D01*
X959431Y-502577D01*
X958121Y-505495D01*
X957684Y-508119D01*
X966854D01*
G01X979769Y-490619D02*
X978022Y-491202D01*
X976712Y-492661D01*
X975839Y-494410D01*
X975184Y-496744D01*
X974966Y-499369D01*
X975184Y-501994D01*
X975839Y-504328D01*
X976712Y-506078D01*
X978022Y-507536D01*
X979769Y-508119D01*
X981515Y-507536D01*
X982826Y-506078D01*
X983699Y-504328D01*
X984354Y-501994D01*
X984572Y-499369D01*
X984354Y-496744D01*
X983699Y-494410D01*
X982826Y-492661D01*
X981515Y-491202D01*
X979769Y-490619D01*
G01X997269Y-508119D02*
Y-490619D01*
X994649Y-494119D01*
G01Y-508119D02*
X999889D01*
G01X1017389D02*
Y-490619D01*
X1009310Y-503161D01*
X1020228D01*
G01X904966Y-463119D02*
Y-445619D01*
X909332D01*
X911079Y-446494D01*
X912389Y-447661D01*
X913481Y-449410D01*
X914354Y-451453D01*
X914572Y-454369D01*
X914354Y-457286D01*
X913481Y-459328D01*
X912389Y-461078D01*
X911079Y-462244D01*
X909332Y-463119D01*
X904966D01*
G01X931199D02*
Y-451453D01*
G01Y-453494D02*
X930326Y-452328D01*
X929015Y-451744D01*
X927487Y-451453D01*
X925959Y-452036D01*
X924649Y-453202D01*
X923775Y-454952D01*
X923339Y-457286D01*
X923775Y-459619D01*
X924649Y-461369D01*
X925959Y-462536D01*
X927487Y-463119D01*
X929015Y-462827D01*
X930326Y-461953D01*
X931199Y-460786D01*
G01X944769Y-445619D02*
Y-463119D01*
G01X941712Y-451453D02*
X947826D01*
G01X958994Y-455244D02*
X965981D01*
X965326Y-453202D01*
X964234Y-452036D01*
X962706Y-451453D01*
X961177Y-451744D01*
X959867Y-452619D01*
X958994Y-454661D01*
X958557Y-456411D01*
Y-458161D01*
X958994Y-459911D01*
X960086Y-461661D01*
X961396Y-462827D01*
X962924Y-463119D01*
X964452Y-462536D01*
X965981Y-460786D01*
M02*
